FILE_TYPE = MACRO_DRAWING;
SET COLOR_WIRE YELLOW;
SET COLOR_PROP MONO;
SET COLOR_DOT WHITE;
SET COLOR_ARC YELLOW;
SET COLOR_BODY GREEN;
SET COLOR_NOTE MONO;
SET PROP_DISPLAY VALUE;
SET PAGE_NUMBER P151;
FORCEADD OFFPAGE..3
R 2
(1500 -450);
FORCEPROP 2 LAST $XR0 143 
J 0
(1220 -450);
DISPLAY 0.638298 (1220 -450);
PAINT MONO (1220 -450);
FORCEPROP 1 LAST COMMENT_BODY TRUE
J 2
(1550 -550);
DISPLAY 1.170213 (1550 -550);
PAINT GREEN (1550 -550);
DISPLAY INVISIBLE (1550 -550);
FORCEPROP 1 LAST OFFPAGE TRUE
J 2
(1175 -575);
PAINT GREEN (1175 -575);
DISPLAY INVISIBLE (1175 -575);
FORCEPROP 2 LAST BOM_COST SM_CONTROLLER
J 2
(1025 -400);
PAINT MONO (1025 -400);
DISPLAY INVISIBLE (1025 -400);
FORCEPROP 2 LAST ROOM BMC
J 2
(1025 -400);
PAINT MONO (1025 -400);
DISPLAY INVISIBLE (1025 -400);
FORCEPROP 2 LAST CDS_LIB mstr_standard
J 0
(1500 -450);
PAINT MONO (1500 -450);
DISPLAY INVISIBLE (1500 -450);
FORCEPROP 2 LAST PATH I100
J 0
(1200 -400);
DISPLAY 1.021277 (1200 -400);
PAINT ORANGE (1200 -400);
DISPLAY INVISIBLE (1200 -400);
FORCEADD RES..2
(950 -100);
FORCEPROP 1 LAST PACK_TYPE 0402
J 0
(990 -175);
DISPLAY 0.617021 (990 -175);
PAINT SKYBLUE (990 -175);
FORCEPROP 1 LAST MATERIAL CHIP
J 0
(990 -125);
DISPLAY 0.617021 (990 -125);
PAINT SKYBLUE (990 -125);
FORCEPROP 1 LAST TOLERANCE 1.0%
J 0
(995 -75);
DISPLAY 0.617021 (995 -75);
PAINT SKYBLUE (995 -75);
FORCEPROP 1 LAST LOCATION R25W117
J 0
(995 25);
DISPLAY 0.617021 (995 25);
PAINT AQUA (995 25);
FORCEPROP 1 LASTPIN (950 0) $PN 1
J 0
(955 -38);
DISPLAY 0.787234 (955 -38);
PAINT ORANGE (955 -38);
FORCEPROP 1 LASTPIN (950 -200) $PN 2
J 0
(955 -190);
DISPLAY 0.787234 (955 -190);
PAINT ORANGE (955 -190);
FORCEPROP 1 LAST VALUE 240
J 0
(995 -25);
DISPLAY 0.617021 (995 -25);
PAINT SKYBLUE (995 -25);
FORCEPROP 1 LAST PART_NUMBER G21796-294
J 0
(990 -225);
DISPLAY 0.617021 (990 -225);
PAINT BLUE (990 -225);
FORCEPROP 1 LAST WATTAGE 1/16W
J 0
(990 -275);
DISPLAY 0.617021 (990 -275);
PAINT SKYBLUE (990 -275);
FORCEPROP 2 LAST BOM_COST SM_MEM
J 0
(1000 125);
DISPLAY 1.021277 (1000 125);
PAINT ORANGE (1000 125);
DISPLAY INVISIBLE (1000 125);
FORCEPROP 2 LAST ROOM BMC_MEMORY
J 0
(1000 75);
DISPLAY 1.021277 (1000 75);
PAINT ORANGE (1000 75);
DISPLAY INVISIBLE (1000 75);
FORCEPROP 2 LAST CDS_LIB mstr_discrete
R 3
J 0
(950 -100);
PAINT MONO (950 -100);
DISPLAY INVISIBLE (950 -100);
FORCEPROP 0 LAST CDS_LOCATION R25W117
J 0
(1000 100);
PAINT MONO (1000 100);
DISPLAY INVISIBLE (1000 100);
FORCEPROP 1 LAST PATH I101
J 0
(1000 75);
DISPLAY 0.978723 (1000 75);
PAINT WHITE (1000 75);
DISPLAY INVISIBLE (1000 75);
FORCEPROP 0 LAST SEC 1
J 0
(1000 100);
PAINT MONO (1000 100);
DISPLAY INVISIBLE (1000 100);
FORCEPROP 2 LAST SEC_TYPE 0402
J 0
(1000 125);
DISPLAY 1.021277 (1000 125);
PAINT ORANGE (1000 125);
DISPLAY INVISIBLE (1000 125);
FORCEADD OFFPAGE..3
R 2
(1500 -550);
FORCEPROP 2 LAST $XR0 143 
J 0
(1220 -550);
DISPLAY 0.638298 (1220 -550);
PAINT MONO (1220 -550);
FORCEPROP 1 LAST COMMENT_BODY TRUE
J 2
(1550 -650);
DISPLAY 1.170213 (1550 -650);
PAINT GREEN (1550 -650);
DISPLAY INVISIBLE (1550 -650);
FORCEPROP 1 LAST OFFPAGE TRUE
J 2
(1175 -675);
PAINT GREEN (1175 -675);
DISPLAY INVISIBLE (1175 -675);
FORCEPROP 2 LAST BOM_COST SM_CONTROLLER
J 2
(1025 -500);
PAINT MONO (1025 -500);
DISPLAY INVISIBLE (1025 -500);
FORCEPROP 2 LAST ROOM BMC
J 2
(1025 -500);
PAINT MONO (1025 -500);
DISPLAY INVISIBLE (1025 -500);
FORCEPROP 2 LAST CDS_LIB mstr_standard
J 0
(1500 -550);
PAINT MONO (1500 -550);
DISPLAY INVISIBLE (1500 -550);
FORCEPROP 2 LAST PATH I103
J 0
(1200 -500);
DISPLAY 1.021277 (1200 -500);
PAINT ORANGE (1200 -500);
DISPLAY INVISIBLE (1200 -500);
FORCEADD OFFPAGE..3
R 2
(1500 -600);
FORCEPROP 2 LAST $XR0 143 
J 0
(1220 -600);
DISPLAY 0.638298 (1220 -600);
PAINT MONO (1220 -600);
FORCEPROP 1 LAST COMMENT_BODY TRUE
J 2
(1550 -700);
DISPLAY 1.170213 (1550 -700);
PAINT GREEN (1550 -700);
DISPLAY INVISIBLE (1550 -700);
FORCEPROP 1 LAST OFFPAGE TRUE
J 2
(1175 -725);
PAINT GREEN (1175 -725);
DISPLAY INVISIBLE (1175 -725);
FORCEPROP 2 LAST BOM_COST SM_CONTROLLER
J 2
(1025 -550);
PAINT MONO (1025 -550);
DISPLAY INVISIBLE (1025 -550);
FORCEPROP 2 LAST ROOM BMC
J 2
(1025 -550);
PAINT MONO (1025 -550);
DISPLAY INVISIBLE (1025 -550);
FORCEPROP 2 LAST CDS_LIB mstr_standard
J 0
(1500 -600);
PAINT MONO (1500 -600);
DISPLAY INVISIBLE (1500 -600);
FORCEPROP 2 LAST PATH I104
J 0
(1200 -550);
DISPLAY 1.021277 (1200 -550);
PAINT ORANGE (1200 -550);
DISPLAY INVISIBLE (1200 -550);
FORCEADD OFFPAGE..3
R 2
(1500 -650);
FORCEPROP 2 LAST $XR0 143 
J 0
(1220 -650);
DISPLAY 0.638298 (1220 -650);
PAINT MONO (1220 -650);
FORCEPROP 1 LAST COMMENT_BODY TRUE
J 2
(1550 -750);
DISPLAY 1.170213 (1550 -750);
PAINT GREEN (1550 -750);
DISPLAY INVISIBLE (1550 -750);
FORCEPROP 1 LAST OFFPAGE TRUE
J 2
(1175 -775);
PAINT GREEN (1175 -775);
DISPLAY INVISIBLE (1175 -775);
FORCEPROP 2 LAST BOM_COST SM_CONTROLLER
J 2
(1025 -600);
PAINT MONO (1025 -600);
DISPLAY INVISIBLE (1025 -600);
FORCEPROP 2 LAST ROOM BMC
J 2
(1025 -600);
PAINT MONO (1025 -600);
DISPLAY INVISIBLE (1025 -600);
FORCEPROP 2 LAST CDS_LIB mstr_standard
J 0
(1500 -650);
PAINT MONO (1500 -650);
DISPLAY INVISIBLE (1500 -650);
FORCEPROP 2 LAST PATH I105
J 0
(1200 -600);
DISPLAY 1.021277 (1200 -600);
PAINT ORANGE (1200 -600);
DISPLAY INVISIBLE (1200 -600);
FORCEADD OFFPAGE..3
R 2
(1500 -700);
FORCEPROP 2 LAST $XR0 143 
J 0
(1220 -700);
DISPLAY 0.638298 (1220 -700);
PAINT MONO (1220 -700);
FORCEPROP 1 LAST COMMENT_BODY TRUE
J 2
(1550 -800);
DISPLAY 1.170213 (1550 -800);
PAINT GREEN (1550 -800);
DISPLAY INVISIBLE (1550 -800);
FORCEPROP 1 LAST OFFPAGE TRUE
J 2
(1175 -825);
PAINT GREEN (1175 -825);
DISPLAY INVISIBLE (1175 -825);
FORCEPROP 2 LAST BOM_COST SM_CONTROLLER
J 2
(1025 -650);
PAINT MONO (1025 -650);
DISPLAY INVISIBLE (1025 -650);
FORCEPROP 2 LAST ROOM BMC
J 2
(1025 -650);
PAINT MONO (1025 -650);
DISPLAY INVISIBLE (1025 -650);
FORCEPROP 2 LAST CDS_LIB mstr_standard
J 0
(1500 -700);
PAINT MONO (1500 -700);
DISPLAY INVISIBLE (1500 -700);
FORCEPROP 2 LAST PATH I106
J 0
(1200 -650);
DISPLAY 1.021277 (1200 -650);
PAINT ORANGE (1200 -650);
DISPLAY INVISIBLE (1200 -650);
FORCEADD OFFPAGE..3
R 2
(1500 -750);
FORCEPROP 2 LAST $XR0 143 
J 0
(1220 -750);
DISPLAY 0.638298 (1220 -750);
PAINT MONO (1220 -750);
FORCEPROP 1 LAST COMMENT_BODY TRUE
J 2
(1550 -850);
DISPLAY 1.170213 (1550 -850);
PAINT GREEN (1550 -850);
DISPLAY INVISIBLE (1550 -850);
FORCEPROP 1 LAST OFFPAGE TRUE
J 2
(1175 -875);
PAINT GREEN (1175 -875);
DISPLAY INVISIBLE (1175 -875);
FORCEPROP 2 LAST BOM_COST SM_CONTROLLER
J 2
(1025 -700);
PAINT MONO (1025 -700);
DISPLAY INVISIBLE (1025 -700);
FORCEPROP 2 LAST ROOM BMC
J 2
(1025 -700);
PAINT MONO (1025 -700);
DISPLAY INVISIBLE (1025 -700);
FORCEPROP 2 LAST CDS_LIB mstr_standard
J 0
(1500 -750);
PAINT MONO (1500 -750);
DISPLAY INVISIBLE (1500 -750);
FORCEPROP 2 LAST PATH I107
J 0
(1200 -700);
DISPLAY 1.021277 (1200 -700);
PAINT ORANGE (1200 -700);
DISPLAY INVISIBLE (1200 -700);
FORCEADD OFFPAGE..3
R 2
(1500 -800);
FORCEPROP 2 LAST $XR0 143 
J 0
(1220 -800);
DISPLAY 0.638298 (1220 -800);
PAINT MONO (1220 -800);
FORCEPROP 1 LAST COMMENT_BODY TRUE
J 2
(1550 -900);
DISPLAY 1.170213 (1550 -900);
PAINT GREEN (1550 -900);
DISPLAY INVISIBLE (1550 -900);
FORCEPROP 1 LAST OFFPAGE TRUE
J 2
(1175 -925);
PAINT GREEN (1175 -925);
DISPLAY INVISIBLE (1175 -925);
FORCEPROP 2 LAST BOM_COST SM_CONTROLLER
J 2
(1025 -750);
PAINT MONO (1025 -750);
DISPLAY INVISIBLE (1025 -750);
FORCEPROP 2 LAST ROOM BMC
J 2
(1025 -750);
PAINT MONO (1025 -750);
DISPLAY INVISIBLE (1025 -750);
FORCEPROP 2 LAST CDS_LIB mstr_standard
J 0
(1500 -800);
PAINT MONO (1500 -800);
DISPLAY INVISIBLE (1500 -800);
FORCEPROP 2 LAST PATH I108
J 0
(1200 -750);
DISPLAY 1.021277 (1200 -750);
PAINT ORANGE (1200 -750);
DISPLAY INVISIBLE (1200 -750);
FORCEADD OFFPAGE..3
R 2
(1500 -900);
FORCEPROP 2 LAST $XR0 143 
J 0
(1220 -900);
DISPLAY 0.638298 (1220 -900);
PAINT MONO (1220 -900);
FORCEPROP 1 LAST COMMENT_BODY TRUE
J 2
(1550 -1000);
DISPLAY 1.170213 (1550 -1000);
PAINT GREEN (1550 -1000);
DISPLAY INVISIBLE (1550 -1000);
FORCEPROP 1 LAST OFFPAGE TRUE
J 2
(1175 -1025);
PAINT GREEN (1175 -1025);
DISPLAY INVISIBLE (1175 -1025);
FORCEPROP 2 LAST BOM_COST SM_CONTROLLER
J 2
(1025 -850);
PAINT MONO (1025 -850);
DISPLAY INVISIBLE (1025 -850);
FORCEPROP 2 LAST ROOM BMC
J 2
(1025 -850);
PAINT MONO (1025 -850);
DISPLAY INVISIBLE (1025 -850);
FORCEPROP 2 LAST CDS_LIB mstr_standard
J 0
(1500 -900);
PAINT MONO (1500 -900);
DISPLAY INVISIBLE (1500 -900);
FORCEPROP 2 LAST PATH I109
J 0
(1200 -850);
DISPLAY 1.021277 (1200 -850);
PAINT ORANGE (1200 -850);
DISPLAY INVISIBLE (1200 -850);
FORCEADD OFFPAGE..3
R 2
(1500 -1000);
FORCEPROP 2 LAST $XR0 143 
J 0
(1220 -1000);
DISPLAY 0.638298 (1220 -1000);
PAINT MONO (1220 -1000);
FORCEPROP 1 LAST COMMENT_BODY TRUE
J 2
(1550 -1100);
DISPLAY 1.170213 (1550 -1100);
PAINT GREEN (1550 -1100);
DISPLAY INVISIBLE (1550 -1100);
FORCEPROP 1 LAST OFFPAGE TRUE
J 2
(1175 -1125);
PAINT GREEN (1175 -1125);
DISPLAY INVISIBLE (1175 -1125);
FORCEPROP 2 LAST PATH I110
J 0
(1200 -950);
DISPLAY 1.021277 (1200 -950);
PAINT ORANGE (1200 -950);
DISPLAY INVISIBLE (1200 -950);
FORCEPROP 2 LAST CDS_LIB mstr_standard
J 0
(1500 -1000);
PAINT MONO (1500 -1000);
DISPLAY INVISIBLE (1500 -1000);
FORCEPROP 2 LAST ROOM BMC
J 2
(1025 -950);
PAINT MONO (1025 -950);
DISPLAY INVISIBLE (1025 -950);
FORCEPROP 2 LAST BOM_COST SM_CONTROLLER
J 2
(1025 -950);
PAINT MONO (1025 -950);
DISPLAY INVISIBLE (1025 -950);
FORCEADD OFFPAGE..3
R 2
(1500 -950);
FORCEPROP 2 LAST $XR0 143 
J 0
(1220 -950);
DISPLAY 0.638298 (1220 -950);
PAINT MONO (1220 -950);
FORCEPROP 1 LAST COMMENT_BODY TRUE
J 2
(1550 -1050);
DISPLAY 1.170213 (1550 -1050);
PAINT GREEN (1550 -1050);
DISPLAY INVISIBLE (1550 -1050);
FORCEPROP 1 LAST OFFPAGE TRUE
J 2
(1175 -1075);
PAINT GREEN (1175 -1075);
DISPLAY INVISIBLE (1175 -1075);
FORCEPROP 2 LAST BOM_COST SM_CONTROLLER
J 2
(1025 -900);
PAINT MONO (1025 -900);
DISPLAY INVISIBLE (1025 -900);
FORCEPROP 2 LAST ROOM BMC
J 2
(1025 -900);
PAINT MONO (1025 -900);
DISPLAY INVISIBLE (1025 -900);
FORCEPROP 2 LAST CDS_LIB mstr_standard
J 0
(1500 -950);
PAINT MONO (1500 -950);
DISPLAY INVISIBLE (1500 -950);
FORCEPROP 2 LAST PATH I111
J 0
(1200 -900);
DISPLAY 1.021277 (1200 -900);
PAINT ORANGE (1200 -900);
DISPLAY INVISIBLE (1200 -900);
FORCEADD GND..1
(950 -300);
FORCEPROP 3 LASTPIN (950 -250) SIG_NAME GND\g
J 0
(960 -240);
DISPLAY 0.659574 (960 -240);
PAINT MONO (960 -240);
DISPLAY INVISIBLE (960 -240);
FORCEPROP 1 LAST HDL_POWER GND
J 0
(950 -150);
DISPLAY 0.872340 (950 -150);
PAINT GREEN (950 -150);
DISPLAY INVISIBLE (950 -150);
FORCEPROP 1 LAST BODY_TYPE PLUMBING
J 0
(905 -343);
DISPLAY 0.340426 (905 -343);
PAINT GREEN (905 -343);
DISPLAY INVISIBLE (905 -343);
FORCEPROP 1 LAST PATH I112
J 0
(1025 -300);
DISPLAY 0.872340 (1025 -300);
PAINT AQUA (1025 -300);
DISPLAY INVISIBLE (1025 -300);
FORCEPROP 1 LAST VOLTAGE 0.0V
J 0
(905 -343);
DISPLAY 0.340426 (905 -343);
PAINT GREEN (905 -343);
DISPLAY INVISIBLE (905 -343);
FORCEPROP 2 LAST CDS_LIB mstr_symbols
J 0
(950 -300);
PAINT MONO (950 -300);
DISPLAY INVISIBLE (950 -300);
FORCEPROP 1 LAST SIZE 1B
J 0
(1025 -350);
DISPLAY 0.872340 (1025 -350);
PAINT AQUA (1025 -350);
DISPLAY INVISIBLE (1025 -350);
FORCEADD OFFPAGE..3
R 2
(1500 -1050);
FORCEPROP 2 LAST $XR0 143 
J 0
(1220 -1050);
DISPLAY 0.638298 (1220 -1050);
PAINT MONO (1220 -1050);
FORCEPROP 1 LAST COMMENT_BODY TRUE
J 2
(1550 -1150);
DISPLAY 1.170213 (1550 -1150);
PAINT GREEN (1550 -1150);
DISPLAY INVISIBLE (1550 -1150);
FORCEPROP 1 LAST OFFPAGE TRUE
J 2
(1175 -1175);
PAINT GREEN (1175 -1175);
DISPLAY INVISIBLE (1175 -1175);
FORCEPROP 2 LAST BOM_COST SM_CONTROLLER
J 2
(1025 -1000);
PAINT MONO (1025 -1000);
DISPLAY INVISIBLE (1025 -1000);
FORCEPROP 2 LAST ROOM BMC
J 2
(1025 -1000);
PAINT MONO (1025 -1000);
DISPLAY INVISIBLE (1025 -1000);
FORCEPROP 2 LAST CDS_LIB mstr_standard
J 0
(1500 -1050);
PAINT MONO (1500 -1050);
DISPLAY INVISIBLE (1500 -1050);
FORCEPROP 2 LAST PATH I113
J 0
(1200 -1000);
DISPLAY 1.021277 (1200 -1000);
PAINT ORANGE (1200 -1000);
DISPLAY INVISIBLE (1200 -1000);
FORCEADD OFFPAGE..3
R 2
(1500 -1200);
FORCEPROP 2 LAST $XR0 143 
J 0
(1220 -1200);
DISPLAY 0.638298 (1220 -1200);
PAINT MONO (1220 -1200);
FORCEPROP 1 LAST COMMENT_BODY TRUE
J 2
(1550 -1300);
DISPLAY 1.170213 (1550 -1300);
PAINT GREEN (1550 -1300);
DISPLAY INVISIBLE (1550 -1300);
FORCEPROP 1 LAST OFFPAGE TRUE
J 2
(1175 -1325);
PAINT GREEN (1175 -1325);
DISPLAY INVISIBLE (1175 -1325);
FORCEPROP 2 LAST CDS_LIB mstr_standard
J 0
(1500 -1200);
PAINT MONO (1500 -1200);
DISPLAY INVISIBLE (1500 -1200);
FORCEPROP 2 LAST ROOM BMC
J 2
(1025 -1150);
PAINT MONO (1025 -1150);
DISPLAY INVISIBLE (1025 -1150);
FORCEPROP 2 LAST BOM_COST SM_CONTROLLER
J 2
(1025 -1150);
PAINT MONO (1025 -1150);
DISPLAY INVISIBLE (1025 -1150);
FORCEPROP 2 LAST PATH I114
J 0
(1200 -1150);
DISPLAY 1.021277 (1200 -1150);
PAINT ORANGE (1200 -1150);
DISPLAY INVISIBLE (1200 -1150);
FORCEADD OFFPAGE..3
R 2
(1500 -1150);
FORCEPROP 2 LAST $XR0 143 
J 0
(1220 -1150);
DISPLAY 0.638298 (1220 -1150);
PAINT MONO (1220 -1150);
FORCEPROP 1 LAST COMMENT_BODY TRUE
J 2
(1550 -1250);
DISPLAY 1.170213 (1550 -1250);
PAINT GREEN (1550 -1250);
DISPLAY INVISIBLE (1550 -1250);
FORCEPROP 1 LAST OFFPAGE TRUE
J 2
(1175 -1275);
PAINT GREEN (1175 -1275);
DISPLAY INVISIBLE (1175 -1275);
FORCEPROP 2 LAST CDS_LIB mstr_standard
J 0
(1500 -1150);
PAINT MONO (1500 -1150);
DISPLAY INVISIBLE (1500 -1150);
FORCEPROP 2 LAST ROOM BMC
J 2
(1025 -1100);
PAINT MONO (1025 -1100);
DISPLAY INVISIBLE (1025 -1100);
FORCEPROP 2 LAST BOM_COST SM_CONTROLLER
J 2
(1025 -1100);
PAINT MONO (1025 -1100);
DISPLAY INVISIBLE (1025 -1100);
FORCEPROP 2 LAST PATH I115
J 0
(1200 -1100);
DISPLAY 1.021277 (1200 -1100);
PAINT ORANGE (1200 -1100);
DISPLAY INVISIBLE (1200 -1100);
FORCEADD OFFPAGE..3
R 2
(1500 -1400);
FORCEPROP 2 LAST $XR1 151 
J 0
(1100 -1400);
DISPLAY 0.638298 (1100 -1400);
PAINT MONO (1100 -1400);
FORCEPROP 2 LAST $XR0 143 
J 0
(1220 -1400);
DISPLAY 0.638298 (1220 -1400);
PAINT MONO (1220 -1400);
FORCEPROP 1 LAST COMMENT_BODY TRUE
J 2
(1550 -1500);
DISPLAY 1.170213 (1550 -1500);
PAINT GREEN (1550 -1500);
DISPLAY INVISIBLE (1550 -1500);
FORCEPROP 1 LAST OFFPAGE TRUE
J 2
(1175 -1525);
PAINT GREEN (1175 -1525);
DISPLAY INVISIBLE (1175 -1525);
FORCEPROP 2 LAST BOM_COST SM_CONTROLLER
J 2
(1025 -1350);
PAINT MONO (1025 -1350);
DISPLAY INVISIBLE (1025 -1350);
FORCEPROP 2 LAST ROOM BMC
J 2
(1025 -1350);
PAINT MONO (1025 -1350);
DISPLAY INVISIBLE (1025 -1350);
FORCEPROP 2 LAST CDS_LIB mstr_standard
J 0
(1500 -1400);
PAINT MONO (1500 -1400);
DISPLAY INVISIBLE (1500 -1400);
FORCEPROP 2 LAST PATH I116
J 0
(1200 -1350);
DISPLAY 1.021277 (1200 -1350);
PAINT ORANGE (1200 -1350);
DISPLAY INVISIBLE (1200 -1350);
FORCEADD OFFPAGE..3
R 2
(1500 -1350);
FORCEPROP 2 LAST $XR1 151 
J 0
(1100 -1350);
DISPLAY 0.638298 (1100 -1350);
PAINT MONO (1100 -1350);
FORCEPROP 2 LAST $XR0 143 
J 0
(1220 -1350);
DISPLAY 0.638298 (1220 -1350);
PAINT MONO (1220 -1350);
FORCEPROP 1 LAST COMMENT_BODY TRUE
J 2
(1550 -1450);
DISPLAY 1.170213 (1550 -1450);
PAINT GREEN (1550 -1450);
DISPLAY INVISIBLE (1550 -1450);
FORCEPROP 1 LAST OFFPAGE TRUE
J 2
(1175 -1475);
PAINT GREEN (1175 -1475);
DISPLAY INVISIBLE (1175 -1475);
FORCEPROP 2 LAST BOM_COST SM_CONTROLLER
J 2
(1025 -1300);
PAINT MONO (1025 -1300);
DISPLAY INVISIBLE (1025 -1300);
FORCEPROP 2 LAST ROOM BMC
J 2
(1025 -1300);
PAINT MONO (1025 -1300);
DISPLAY INVISIBLE (1025 -1300);
FORCEPROP 2 LAST CDS_LIB mstr_standard
J 0
(1500 -1350);
PAINT MONO (1500 -1350);
DISPLAY INVISIBLE (1500 -1350);
FORCEPROP 2 LAST PATH I117
J 0
(1200 -1300);
DISPLAY 1.021277 (1200 -1300);
PAINT ORANGE (1200 -1300);
DISPLAY INVISIBLE (1200 -1300);
FORCEADD GND..1
(600 -300);
FORCEPROP 3 LASTPIN (600 -250) SIG_NAME GND\g
J 0
(610 -240);
DISPLAY 0.659574 (610 -240);
PAINT MONO (610 -240);
DISPLAY INVISIBLE (610 -240);
FORCEPROP 1 LAST HDL_POWER GND
J 0
(600 -150);
DISPLAY 0.872340 (600 -150);
PAINT GREEN (600 -150);
DISPLAY INVISIBLE (600 -150);
FORCEPROP 1 LAST BODY_TYPE PLUMBING
J 0
(555 -343);
DISPLAY 0.340426 (555 -343);
PAINT GREEN (555 -343);
DISPLAY INVISIBLE (555 -343);
FORCEPROP 1 LAST SIZE 1B
J 0
(675 -350);
DISPLAY 0.872340 (675 -350);
PAINT AQUA (675 -350);
DISPLAY INVISIBLE (675 -350);
FORCEPROP 2 LAST CDS_LIB mstr_symbols
J 0
(600 -300);
PAINT MONO (600 -300);
DISPLAY INVISIBLE (600 -300);
FORCEPROP 1 LAST VOLTAGE 0.0V
J 0
(555 -343);
DISPLAY 0.340426 (555 -343);
PAINT GREEN (555 -343);
DISPLAY INVISIBLE (555 -343);
FORCEPROP 1 LAST PATH I118
J 0
(675 -300);
DISPLAY 0.872340 (675 -300);
PAINT AQUA (675 -300);
DISPLAY INVISIBLE (675 -300);
FORCEADD SC1U16V3KX-2GP..1
(-2500 2100);
FORCEPROP 1 LAST VALUE SC1U16V3KX-2GP
J 0
(-2450 2175);
DISPLAY 0.617021 (-2450 2175);
PAINT GREEN (-2450 2175);
FORCEPROP 0 LASTPIN (-2500 2025) $PN 2
R 1
J 2
(-2510 2015);
DISPLAY 0.808511 (-2510 2015);
PAINT MONO (-2510 2015);
FORCEPROP 0 LASTPIN (-2500 2175) $PN 1
R 1
J 0
(-2510 2185);
DISPLAY 0.808511 (-2510 2185);
PAINT MONO (-2510 2185);
FORCEPROP 2 LAST PACK_SIZE 0603
J 0
(-2450 1925);
DISPLAY 0.638298 (-2450 1925);
PAINT GREEN (-2450 1925);
FORCEPROP 2 LAST TYPE X5R
J 0
(-2450 1975);
DISPLAY 0.638298 (-2450 1975);
PAINT GREEN (-2450 1975);
FORCEPROP 2 LAST RATED 16V
J 0
(-2450 2025);
DISPLAY 0.638298 (-2450 2025);
PAINT GREEN (-2450 2025);
FORCEPROP 1 LAST LOCATION C25W17
J 0
(-2450 2230);
DISPLAY 0.617021 (-2450 2230);
PAINT GREEN (-2450 2230);
FORCEPROP 2 LAST TOLERANCE 10%
J 0
(-2450 2075);
DISPLAY 0.638298 (-2450 2075);
PAINT GREEN (-2450 2075);
FORCEPROP 2 LAST ATTRIBUTE 1UF
J 0
(-2450 2125);
DISPLAY 0.638298 (-2450 2125);
PAINT GREEN (-2450 2125);
FORCEPROP 0 LAST CDS_SEC 1
J 0
(-2475 2100);
PAINT MONO (-2475 2100);
DISPLAY INVISIBLE (-2475 2100);
FORCEPROP 0 LAST $SEC 1
J 0
(-2475 2100);
PAINT MONO (-2475 2100);
DISPLAY INVISIBLE (-2475 2100);
FORCEPROP 0 LAST CDS_LOCATION C25W17
J 0
(-2475 2100);
PAINT MONO (-2475 2100);
DISPLAY INVISIBLE (-2475 2100);
FORCEPROP 1 LAST PACK_TYPE SMD-BCG
J 0
(-2500 2100);
DISPLAY 0.617021 (-2500 2100);
PAINT GREEN (-2500 2100);
DISPLAY INVISIBLE (-2500 2100);
FORCEPROP 1 LAST PART_NUMBER 78.10521.5BL
J 0
(-2500 2100);
DISPLAY 0.617021 (-2500 2100);
PAINT GREEN (-2500 2100);
DISPLAY INVISIBLE (-2500 2100);
FORCEPROP 1 LAST CDS_LMAN_SYM_OUTLINE -50,25,50,-25
J 0
(-2500 2100);
DISPLAY 0.468085 (-2500 2100);
PAINT GREEN (-2500 2100);
DISPLAY INVISIBLE (-2500 2100);
FORCEPROP 2 LAST CDS_LIB w_hdl
J 0
(-2500 2100);
PAINT MONO (-2500 2100);
DISPLAY INVISIBLE (-2500 2100);
FORCEPROP 1 LAST PATH I120
J 0
(-2500 2100);
DISPLAY 0.617021 (-2500 2100);
PAINT GREEN (-2500 2100);
DISPLAY INVISIBLE (-2500 2100);
FORCEADD SC1U16V3KX-2GP..1
(-2925 2100);
FORCEPROP 2 LAST RATED 16V
J 0
(-2875 2025);
DISPLAY 0.638298 (-2875 2025);
PAINT GREEN (-2875 2025);
FORCEPROP 0 LASTPIN (-2925 2175) $PN 1
R 1
J 0
(-2935 2185);
DISPLAY 0.808511 (-2935 2185);
PAINT MONO (-2935 2185);
FORCEPROP 1 LAST VALUE SC1U16V3KX-2GP
J 0
(-2875 2175);
DISPLAY 0.617021 (-2875 2175);
PAINT GREEN (-2875 2175);
FORCEPROP 2 LAST ATTRIBUTE 1UF
J 0
(-2875 2125);
DISPLAY 0.638298 (-2875 2125);
PAINT GREEN (-2875 2125);
FORCEPROP 1 LAST LOCATION C25W18
J 0
(-2875 2230);
DISPLAY 0.617021 (-2875 2230);
PAINT GREEN (-2875 2230);
FORCEPROP 2 LAST TOLERANCE 10%
J 0
(-2875 2075);
DISPLAY 0.638298 (-2875 2075);
PAINT GREEN (-2875 2075);
FORCEPROP 2 LAST TYPE X5R
J 0
(-2875 1975);
DISPLAY 0.638298 (-2875 1975);
PAINT GREEN (-2875 1975);
FORCEPROP 2 LAST PACK_SIZE 0603
J 0
(-2875 1925);
DISPLAY 0.638298 (-2875 1925);
PAINT GREEN (-2875 1925);
FORCEPROP 0 LASTPIN (-2925 2025) $PN 2
R 1
J 2
(-2935 2015);
DISPLAY 0.808511 (-2935 2015);
PAINT MONO (-2935 2015);
FORCEPROP 1 LAST PACK_TYPE SMD-BCG
J 0
(-2925 2100);
DISPLAY 0.617021 (-2925 2100);
PAINT GREEN (-2925 2100);
DISPLAY INVISIBLE (-2925 2100);
FORCEPROP 1 LAST PART_NUMBER 78.10521.5BL
J 0
(-2925 2100);
DISPLAY 0.617021 (-2925 2100);
PAINT GREEN (-2925 2100);
DISPLAY INVISIBLE (-2925 2100);
FORCEPROP 2 LAST CDS_LIB w_hdl
J 0
(-2925 2100);
PAINT MONO (-2925 2100);
DISPLAY INVISIBLE (-2925 2100);
FORCEPROP 1 LAST CDS_LMAN_SYM_OUTLINE -50,25,50,-25
J 0
(-2925 2100);
DISPLAY 0.468085 (-2925 2100);
PAINT GREEN (-2925 2100);
DISPLAY INVISIBLE (-2925 2100);
FORCEPROP 0 LAST CDS_LOCATION C25W18
J 0
(-2900 2100);
PAINT MONO (-2900 2100);
DISPLAY INVISIBLE (-2900 2100);
FORCEPROP 0 LAST $SEC 1
J 0
(-2900 2100);
PAINT MONO (-2900 2100);
DISPLAY INVISIBLE (-2900 2100);
FORCEPROP 0 LAST CDS_SEC 1
J 0
(-2900 2100);
PAINT MONO (-2900 2100);
DISPLAY INVISIBLE (-2900 2100);
FORCEPROP 1 LAST PATH I121
J 0
(-2925 2100);
DISPLAY 0.617021 (-2925 2100);
PAINT GREEN (-2925 2100);
DISPLAY INVISIBLE (-2925 2100);
FORCEADD W_VCC_CIRCLE..1
(-3225 2300);
FORCEPROP 3 LASTPIN (-3225 2300) SIG_NAME P1V2_AUX_BMC\g
J 0
(-3215 2310);
DISPLAY 0.659574 (-3215 2310);
PAINT MONO (-3215 2310);
DISPLAY INVISIBLE (-3215 2310);
FORCEPROP 1 LAST HDL_POWER P1V2_AUX_BMC
J 1
(-3204 2375);
DISPLAY 0.872340 (-3204 2375);
PAINT ORANGE (-3204 2375);
FORCEPROP 1 LAST BODY_TYPE PLUMBING
J 0
(-3213 2294);
DISPLAY 0.340426 (-3213 2294);
PAINT GREEN (-3213 2294);
DISPLAY INVISIBLE (-3213 2294);
FORCEPROP 1 LAST CDS_LMAN_SYM_OUTLINE -100,100,100,-100
J 0
(-3225 2300);
DISPLAY 0.468085 (-3225 2300);
PAINT GREEN (-3225 2300);
DISPLAY INVISIBLE (-3225 2300);
FORCEPROP 2 LAST CDS_LIB w_power
J 0
(-3225 2300);
PAINT MONO (-3225 2300);
DISPLAY INVISIBLE (-3225 2300);
FORCEPROP 1 LAST PATH I122
J 0
(-3225 2300);
DISPLAY 0.617021 (-3225 2300);
PAINT GREEN (-3225 2300);
DISPLAY INVISIBLE (-3225 2300);
FORCEADD CAP..1
(-3225 2100);
FORCEPROP 1 LAST VALUE 4.7UF
J 0
(-3175 2125);
DISPLAY 0.638298 (-3175 2125);
PAINT SKYBLUE (-3175 2125);
FORCEPROP 1 LAST VOLTAGE 6.3V
J 0
(-3175 2075);
DISPLAY 0.638298 (-3175 2075);
PAINT SKYBLUE (-3175 2075);
FORCEPROP 1 LAST LOCATION C25W19
J 0
(-3175 2175);
DISPLAY 0.638298 (-3175 2175);
PAINT SKYBLUE (-3175 2175);
FORCEPROP 1 LAST PART_NUMBER E15431-003
J 0
(-3175 2225);
DISPLAY 0.638298 (-3175 2225);
PAINT BLUE (-3175 2225);
FORCEPROP 1 LAST PACK_TYPE 0603
J 0
(-3175 1925);
DISPLAY 0.638298 (-3175 1925);
PAINT SKYBLUE (-3175 1925);
FORCEPROP 1 LAST MATERIAL X6S
J 0
(-3175 1975);
DISPLAY 0.638298 (-3175 1975);
PAINT SKYBLUE (-3175 1975);
FORCEPROP 1 LAST TOLERANCE 10%
J 0
(-3175 2025);
DISPLAY 0.638298 (-3175 2025);
PAINT SKYBLUE (-3175 2025);
FORCEPROP 1 LASTPIN (-3225 2200) $PN 1
J 0
(-3215 2180);
DISPLAY 0.787234 (-3215 2180);
PAINT ORANGE (-3215 2180);
FORCEPROP 1 LASTPIN (-3225 2000) $PN 2
J 0
(-3215 1980);
DISPLAY 0.787234 (-3215 1980);
PAINT ORANGE (-3215 1980);
FORCEPROP 2 LAST CDS_LIB mstr_discrete
J 0
(-3225 2100);
PAINT MONO (-3225 2100);
DISPLAY INVISIBLE (-3225 2100);
FORCEPROP 0 LAST CDS_LOCATION C25W19
J 0
(-3175 2275);
PAINT MONO (-3175 2275);
DISPLAY INVISIBLE (-3175 2275);
FORCEPROP 1 LAST PATH I123
J 0
(-3175 2250);
DISPLAY 0.978723 (-3175 2250);
PAINT WHITE (-3175 2250);
DISPLAY INVISIBLE (-3175 2250);
FORCEPROP 0 LAST SEC 1
J 0
(-3175 2275);
PAINT MONO (-3175 2275);
DISPLAY INVISIBLE (-3175 2275);
FORCEPROP 2 LAST SEC_TYPE 0603
J 0
(-3175 2300);
DISPLAY 1.021277 (-3175 2300);
PAINT ORANGE (-3175 2300);
DISPLAY INVISIBLE (-3175 2300);
FORCEADD GND..1
(-3225 1825);
FORCEPROP 3 LASTPIN (-3225 1875) SIG_NAME GND\g
J 0
(-3215 1885);
DISPLAY 0.659574 (-3215 1885);
PAINT MONO (-3215 1885);
DISPLAY INVISIBLE (-3215 1885);
FORCEPROP 1 LAST HDL_POWER GND
J 0
(-3225 1975);
DISPLAY 0.872340 (-3225 1975);
PAINT GREEN (-3225 1975);
DISPLAY INVISIBLE (-3225 1975);
FORCEPROP 1 LAST BODY_TYPE PLUMBING
J 0
(-3270 1782);
DISPLAY 0.340426 (-3270 1782);
PAINT GREEN (-3270 1782);
DISPLAY INVISIBLE (-3270 1782);
FORCEPROP 2 LAST CDS_LIB mstr_symbols
J 0
(-3225 1825);
PAINT MONO (-3225 1825);
DISPLAY INVISIBLE (-3225 1825);
FORCEPROP 1 LAST SIZE 1B
J 0
(-3150 1775);
DISPLAY 0.872340 (-3150 1775);
PAINT AQUA (-3150 1775);
DISPLAY INVISIBLE (-3150 1775);
FORCEPROP 1 LAST VOLTAGE 0.0V
J 0
(-3270 1782);
DISPLAY 0.340426 (-3270 1782);
PAINT GREEN (-3270 1782);
DISPLAY INVISIBLE (-3270 1782);
FORCEPROP 1 LAST PATH I124
J 0
(-3150 1825);
DISPLAY 0.872340 (-3150 1825);
PAINT AQUA (-3150 1825);
DISPLAY INVISIBLE (-3150 1825);
FORCEADD CAP..1
R 1
(325 1675);
FORCEPROP 1 LAST PART_NUMBER D97712-011
R 1
J 0
(475 1725);
DISPLAY 0.617021 (475 1725);
PAINT BLUE (475 1725);
FORCEPROP 1 LAST PACK_TYPE 0402
R 1
J 0
(525 1725);
DISPLAY 0.617021 (525 1725);
PAINT SKYBLUE (525 1725);
FORCEPROP 1 LAST VALUE 1.0UF
R 1
J 0
(275 1725);
DISPLAY 0.617021 (275 1725);
PAINT SKYBLUE (275 1725);
FORCEPROP 1 LAST MATERIAL X6S
R 1
J 0
(425 1725);
DISPLAY 0.617021 (425 1725);
PAINT SKYBLUE (425 1725);
FORCEPROP 1 LAST VOLTAGE 16V
R 1
J 0
(325 1725);
DISPLAY 0.617021 (325 1725);
PAINT SKYBLUE (325 1725);
FORCEPROP 1 LAST TOLERANCE 10%
R 1
J 0
(375 1725);
DISPLAY 0.617021 (375 1725);
PAINT SKYBLUE (375 1725);
FORCEPROP 1 LAST LOCATION C25W1
R 1
J 0
(225 1725);
DISPLAY 0.617021 (225 1725);
PAINT AQUA (225 1725);
FORCEPROP 1 LAST PATH I125
R 1
J 0
(175 1725);
DISPLAY 0.978723 (175 1725);
PAINT WHITE (175 1725);
DISPLAY INVISIBLE (175 1725);
FORCEPROP 0 LAST CDS_SEC 1
R 1
J 0
(425 1750);
PAINT MONO (425 1750);
DISPLAY INVISIBLE (425 1750);
FORCEPROP 0 LAST $SEC 1
R 1
J 0
(425 1750);
PAINT MONO (425 1750);
DISPLAY INVISIBLE (425 1750);
FORCEPROP 0 LAST CDS_LOCATION C25W1
R 1
J 0
(425 1750);
PAINT MONO (425 1750);
DISPLAY INVISIBLE (425 1750);
FORCEPROP 1 LASTPIN (225 1675) $PN 1
R 1
J 0
(245 1685);
DISPLAY 0.787234 (245 1685);
PAINT ORANGE (245 1685);
DISPLAY INVISIBLE (245 1685);
FORCEPROP 1 LASTPIN (425 1675) $PN 2
R 1
J 0
(445 1685);
DISPLAY 0.787234 (445 1685);
PAINT ORANGE (445 1685);
DISPLAY INVISIBLE (445 1685);
FORCEPROP 2 LAST ROOM VDDQ_KLM_PWR_VR
R 1
J 0
(175 1725);
DISPLAY 1.361702 (175 1725);
PAINT ORANGE (175 1725);
DISPLAY INVISIBLE (175 1725);
FORCEPROP 2 LAST CDS_LIB mstr_discrete
R 1
J 0
(325 1675);
PAINT MONO (325 1675);
DISPLAY INVISIBLE (325 1675);
FORCEADD P3V3_STBY..1
(-50 200);
FORCEPROP 3 LASTPIN (-50 150) SIG_NAME P3V3_STBY\g
J 0
(-40 160);
DISPLAY 0.659574 (-40 160);
PAINT MONO (-40 160);
DISPLAY INVISIBLE (-40 160);
FORCEPROP 1 LAST HDL_POWER P3V3_STBY
J 0
(-350 75);
DISPLAY 0.872340 (-350 75);
PAINT ORANGE (-350 75);
DISPLAY INVISIBLE (-350 75);
FORCEPROP 1 LAST BODY_TYPE PLUMBING
J 0
(-95 157);
DISPLAY 0.340426 (-95 157);
PAINT GREEN (-95 157);
DISPLAY INVISIBLE (-95 157);
FORCEPROP 1 LAST VOLTAGE 3.3V
J 0
(-95 157);
DISPLAY 0.340426 (-95 157);
PAINT SKYBLUE (-95 157);
DISPLAY INVISIBLE (-95 157);
FORCEPROP 2 LAST CDS_LIB mstr_symbols
J 0
(-50 200);
PAINT ORANGE (-50 200);
DISPLAY INVISIBLE (-50 200);
FORCEPROP 1 LAST SIZE 1B
J 0
(-5 222);
DISPLAY 0.340426 (-5 222);
PAINT GREEN (-5 222);
DISPLAY INVISIBLE (-5 222);
FORCEPROP 1 LAST PATH I136
J 0
(-5 202);
DISPLAY 0.340426 (-5 202);
PAINT GREEN (-5 202);
DISPLAY INVISIBLE (-5 202);
FORCEADD GND..1
(625 325);
FORCEPROP 3 LASTPIN (625 375) SIG_NAME GND\g
J 0
(635 385);
DISPLAY 0.659574 (635 385);
PAINT MONO (635 385);
DISPLAY INVISIBLE (635 385);
FORCEPROP 1 LAST HDL_POWER GND
J 0
(625 475);
DISPLAY 0.872340 (625 475);
PAINT GREEN (625 475);
DISPLAY INVISIBLE (625 475);
FORCEPROP 1 LAST BODY_TYPE PLUMBING
J 0
(580 282);
DISPLAY 0.340426 (580 282);
PAINT GREEN (580 282);
DISPLAY INVISIBLE (580 282);
FORCEPROP 1 LAST PATH I137
J 0
(700 325);
DISPLAY 0.872340 (700 325);
PAINT AQUA (700 325);
DISPLAY INVISIBLE (700 325);
FORCEPROP 2 LAST CDS_LIB mstr_symbols
J 0
(625 325);
PAINT MONO (625 325);
DISPLAY INVISIBLE (625 325);
FORCEPROP 1 LAST SIZE 1B
J 0
(700 275);
DISPLAY 0.872340 (700 275);
PAINT AQUA (700 275);
DISPLAY INVISIBLE (700 275);
FORCEPROP 1 LAST VOLTAGE 0.0V
J 0
(580 282);
DISPLAY 0.340426 (580 282);
PAINT GREEN (580 282);
DISPLAY INVISIBLE (580 282);
FORCEADD RES..1
(-300 0);
FORCEPROP 1 LAST WATTAGE 1/16W
J 2
(-325 -150);
DISPLAY 0.617021 (-325 -150);
PAINT SKYBLUE (-325 -150);
FORCEPROP 1 LASTPIN (-400 0) $PN 1
J 0
(-388 12);
DISPLAY 0.617021 (-388 12);
PAINT ORANGE (-388 12);
FORCEPROP 1 LAST PACK_TYPE 0402
J 0
(-50 -150);
DISPLAY 0.617021 (-50 -150);
PAINT SKYBLUE (-50 -150);
FORCEPROP 1 LAST VALUE 221
J 2
(-325 -100);
DISPLAY 0.617021 (-325 -100);
PAINT SKYBLUE (-325 -100);
FORCEPROP 1 LAST TOLERANCE 1.0%
J 0
(-300 -100);
DISPLAY 0.617021 (-300 -100);
PAINT SKYBLUE (-300 -100);
FORCEPROP 1 LAST MATERIAL CHIP
J 0
(-300 -150);
DISPLAY 0.617021 (-300 -150);
PAINT SKYBLUE (-300 -150);
FORCEPROP 1 LASTPIN (-200 0) $PN 2
J 0
(-238 12);
DISPLAY 0.617021 (-238 12);
PAINT ORANGE (-238 12);
FORCEPROP 1 LAST LOCATION R9E24
J 0
(-350 50);
DISPLAY 0.617021 (-350 50);
PAINT AQUA (-350 50);
FORCEPROP 1 LAST PART_NUMBER G21796-271
J 0
(-350 100);
DISPLAY 0.617021 (-350 100);
PAINT BLUE (-350 100);
FORCEPROP 0 LAST CDS_SEC 1
J 0
(-350 150);
PAINT MONO (-350 150);
DISPLAY INVISIBLE (-350 150);
FORCEPROP 0 LAST CDS_LOCATION R9E24
J 0
(-350 150);
PAINT MONO (-350 150);
DISPLAY INVISIBLE (-350 150);
FORCEPROP 2 LAST CDS_LIB mstr_discrete
J 0
(-300 0);
PAINT ORANGE (-300 0);
DISPLAY INVISIBLE (-300 0);
FORCEPROP 2 LAST ROOM BMC
J 0
(-350 150);
DISPLAY 1.021277 (-350 150);
PAINT ORANGE (-350 150);
DISPLAY INVISIBLE (-350 150);
FORCEPROP 2 LAST SEC_TYPE 0402
J 0
(-350 200);
DISPLAY 1.021277 (-350 200);
PAINT ORANGE (-350 200);
DISPLAY INVISIBLE (-350 200);
FORCEPROP 2 LAST BOM_COST SM_CONTROLLER
J 0
(-350 200);
DISPLAY 1.021277 (-350 200);
PAINT ORANGE (-350 200);
DISPLAY INVISIBLE (-350 200);
FORCEPROP 2 LAST SEC 1
J 0
(-350 200);
DISPLAY 0.680851 (-350 200);
PAINT MONO (-350 200);
DISPLAY INVISIBLE (-350 200);
FORCEPROP 1 LAST PATH I138
J 0
(-350 150);
DISPLAY 0.978723 (-350 150);
PAINT WHITE (-350 150);
DISPLAY INVISIBLE (-350 150);
FORCEADD CAP..1
R 1
(325 1425);
FORCEPROP 1 LAST VALUE 1.0UF
R 1
J 0
(275 1475);
DISPLAY 0.617021 (275 1475);
PAINT SKYBLUE (275 1475);
FORCEPROP 1 LAST LOCATION C25W2
R 1
J 0
(225 1475);
DISPLAY 0.617021 (225 1475);
PAINT AQUA (225 1475);
FORCEPROP 1 LAST PACK_TYPE 0402
R 1
J 0
(525 1475);
DISPLAY 0.617021 (525 1475);
PAINT SKYBLUE (525 1475);
FORCEPROP 1 LAST PART_NUMBER D97712-011
R 1
J 0
(475 1475);
DISPLAY 0.617021 (475 1475);
PAINT BLUE (475 1475);
FORCEPROP 1 LAST MATERIAL X6S
R 1
J 0
(425 1475);
DISPLAY 0.617021 (425 1475);
PAINT SKYBLUE (425 1475);
FORCEPROP 1 LAST TOLERANCE 10%
R 1
J 0
(375 1475);
DISPLAY 0.617021 (375 1475);
PAINT SKYBLUE (375 1475);
FORCEPROP 1 LAST VOLTAGE 16V
R 1
J 0
(325 1475);
DISPLAY 0.617021 (325 1475);
PAINT SKYBLUE (325 1475);
FORCEPROP 1 LAST PATH I139
R 1
J 0
(175 1475);
DISPLAY 0.978723 (175 1475);
PAINT WHITE (175 1475);
DISPLAY INVISIBLE (175 1475);
FORCEPROP 0 LAST CDS_SEC 1
R 1
J 0
(425 1500);
PAINT MONO (425 1500);
DISPLAY INVISIBLE (425 1500);
FORCEPROP 0 LAST $SEC 1
R 1
J 0
(425 1500);
PAINT MONO (425 1500);
DISPLAY INVISIBLE (425 1500);
FORCEPROP 0 LAST CDS_LOCATION C25W2
R 1
J 0
(425 1500);
PAINT MONO (425 1500);
DISPLAY INVISIBLE (425 1500);
FORCEPROP 1 LASTPIN (225 1425) $PN 1
R 1
J 0
(245 1435);
DISPLAY 0.787234 (245 1435);
PAINT ORANGE (245 1435);
DISPLAY INVISIBLE (245 1435);
FORCEPROP 1 LASTPIN (425 1425) $PN 2
R 1
J 0
(445 1435);
DISPLAY 0.787234 (445 1435);
PAINT ORANGE (445 1435);
DISPLAY INVISIBLE (445 1435);
FORCEPROP 2 LAST ROOM VDDQ_KLM_PWR_VR
R 1
J 0
(175 1475);
DISPLAY 1.361702 (175 1475);
PAINT ORANGE (175 1475);
DISPLAY INVISIBLE (175 1475);
FORCEPROP 2 LAST CDS_LIB mstr_discrete
J 0
(325 1425);
PAINT MONO (325 1425);
DISPLAY INVISIBLE (325 1425);
FORCEADD CAP..1
R 1
(325 1175);
FORCEPROP 1 LAST TOLERANCE 10%
R 1
J 0
(375 1225);
DISPLAY 0.617021 (375 1225);
PAINT SKYBLUE (375 1225);
FORCEPROP 1 LAST MATERIAL X6S
R 1
J 0
(425 1225);
DISPLAY 0.617021 (425 1225);
PAINT SKYBLUE (425 1225);
FORCEPROP 1 LAST PART_NUMBER D97712-011
R 1
J 0
(475 1225);
DISPLAY 0.617021 (475 1225);
PAINT BLUE (475 1225);
FORCEPROP 1 LAST PACK_TYPE 0402
R 1
J 0
(525 1225);
DISPLAY 0.617021 (525 1225);
PAINT SKYBLUE (525 1225);
FORCEPROP 1 LAST VOLTAGE 16V
R 1
J 0
(325 1225);
DISPLAY 0.617021 (325 1225);
PAINT SKYBLUE (325 1225);
FORCEPROP 1 LAST VALUE 1.0UF
R 1
J 0
(275 1225);
DISPLAY 0.617021 (275 1225);
PAINT SKYBLUE (275 1225);
FORCEPROP 1 LAST LOCATION C25W3
R 1
J 0
(225 1225);
DISPLAY 0.617021 (225 1225);
PAINT AQUA (225 1225);
FORCEPROP 1 LAST PATH I140
R 1
J 0
(175 1225);
DISPLAY 0.978723 (175 1225);
PAINT WHITE (175 1225);
DISPLAY INVISIBLE (175 1225);
FORCEPROP 0 LAST CDS_SEC 1
R 1
J 0
(425 1250);
PAINT MONO (425 1250);
DISPLAY INVISIBLE (425 1250);
FORCEPROP 0 LAST $SEC 1
R 1
J 0
(425 1250);
PAINT MONO (425 1250);
DISPLAY INVISIBLE (425 1250);
FORCEPROP 0 LAST CDS_LOCATION C25W3
R 1
J 0
(425 1250);
PAINT MONO (425 1250);
DISPLAY INVISIBLE (425 1250);
FORCEPROP 1 LASTPIN (225 1175) $PN 1
R 1
J 0
(245 1185);
DISPLAY 0.787234 (245 1185);
PAINT ORANGE (245 1185);
DISPLAY INVISIBLE (245 1185);
FORCEPROP 1 LASTPIN (425 1175) $PN 2
R 1
J 0
(445 1185);
DISPLAY 0.787234 (445 1185);
PAINT ORANGE (445 1185);
DISPLAY INVISIBLE (445 1185);
FORCEPROP 2 LAST CDS_LIB mstr_discrete
J 0
(325 1175);
PAINT MONO (325 1175);
DISPLAY INVISIBLE (325 1175);
FORCEPROP 2 LAST ROOM VDDQ_KLM_PWR_VR
R 1
J 0
(175 1225);
DISPLAY 1.361702 (175 1225);
PAINT ORANGE (175 1225);
DISPLAY INVISIBLE (175 1225);
FORCEADD CAP..1
R 1
(325 925);
FORCEPROP 1 LAST PART_NUMBER D97712-011
R 1
J 0
(475 975);
DISPLAY 0.617021 (475 975);
PAINT BLUE (475 975);
FORCEPROP 1 LAST LOCATION C25W4
R 1
J 0
(225 975);
DISPLAY 0.617021 (225 975);
PAINT AQUA (225 975);
FORCEPROP 1 LAST PACK_TYPE 0402
R 1
J 0
(525 975);
DISPLAY 0.617021 (525 975);
PAINT SKYBLUE (525 975);
FORCEPROP 1 LAST VALUE 1.0UF
R 1
J 0
(275 975);
DISPLAY 0.617021 (275 975);
PAINT SKYBLUE (275 975);
FORCEPROP 1 LAST VOLTAGE 16V
R 1
J 0
(325 975);
DISPLAY 0.617021 (325 975);
PAINT SKYBLUE (325 975);
FORCEPROP 1 LAST TOLERANCE 10%
R 1
J 0
(375 975);
DISPLAY 0.617021 (375 975);
PAINT SKYBLUE (375 975);
FORCEPROP 1 LAST MATERIAL X6S
R 1
J 0
(425 975);
DISPLAY 0.617021 (425 975);
PAINT SKYBLUE (425 975);
FORCEPROP 1 LAST PATH I141
R 1
J 0
(175 975);
DISPLAY 0.978723 (175 975);
PAINT WHITE (175 975);
DISPLAY INVISIBLE (175 975);
FORCEPROP 0 LAST CDS_SEC 1
R 1
J 0
(425 1000);
PAINT MONO (425 1000);
DISPLAY INVISIBLE (425 1000);
FORCEPROP 0 LAST $SEC 1
R 1
J 0
(425 1000);
PAINT MONO (425 1000);
DISPLAY INVISIBLE (425 1000);
FORCEPROP 0 LAST CDS_LOCATION C25W4
R 1
J 0
(425 1000);
PAINT MONO (425 1000);
DISPLAY INVISIBLE (425 1000);
FORCEPROP 1 LASTPIN (225 925) $PN 1
R 1
J 0
(245 935);
DISPLAY 0.787234 (245 935);
PAINT ORANGE (245 935);
DISPLAY INVISIBLE (245 935);
FORCEPROP 1 LASTPIN (425 925) $PN 2
R 1
J 0
(445 935);
DISPLAY 0.787234 (445 935);
PAINT ORANGE (445 935);
DISPLAY INVISIBLE (445 935);
FORCEPROP 2 LAST CDS_LIB mstr_discrete
J 0
(325 925);
PAINT MONO (325 925);
DISPLAY INVISIBLE (325 925);
FORCEPROP 2 LAST ROOM VDDQ_KLM_PWR_VR
R 1
J 0
(175 975);
DISPLAY 1.361702 (175 975);
PAINT ORANGE (175 975);
DISPLAY INVISIBLE (175 975);
FORCEADD CAP..1
R 1
(325 675);
FORCEPROP 1 LAST LOCATION C25W5
R 1
J 0
(225 725);
DISPLAY 0.617021 (225 725);
PAINT AQUA (225 725);
FORCEPROP 1 LAST VALUE 1.0UF
R 1
J 0
(275 725);
DISPLAY 0.617021 (275 725);
PAINT SKYBLUE (275 725);
FORCEPROP 1 LAST VOLTAGE 16V
R 1
J 0
(325 725);
DISPLAY 0.617021 (325 725);
PAINT SKYBLUE (325 725);
FORCEPROP 1 LAST TOLERANCE 10%
R 1
J 0
(375 725);
DISPLAY 0.617021 (375 725);
PAINT SKYBLUE (375 725);
FORCEPROP 1 LAST MATERIAL X6S
R 1
J 0
(425 725);
DISPLAY 0.617021 (425 725);
PAINT SKYBLUE (425 725);
FORCEPROP 1 LAST PART_NUMBER D97712-011
R 1
J 0
(475 725);
DISPLAY 0.617021 (475 725);
PAINT BLUE (475 725);
FORCEPROP 1 LAST PACK_TYPE 0402
R 1
J 0
(525 725);
DISPLAY 0.617021 (525 725);
PAINT SKYBLUE (525 725);
FORCEPROP 1 LAST PATH I142
R 1
J 0
(175 725);
DISPLAY 0.978723 (175 725);
PAINT WHITE (175 725);
DISPLAY INVISIBLE (175 725);
FORCEPROP 0 LAST CDS_SEC 1
R 1
J 0
(425 750);
PAINT MONO (425 750);
DISPLAY INVISIBLE (425 750);
FORCEPROP 0 LAST $SEC 1
R 1
J 0
(425 750);
PAINT MONO (425 750);
DISPLAY INVISIBLE (425 750);
FORCEPROP 0 LAST CDS_LOCATION C25W5
R 1
J 0
(425 750);
PAINT MONO (425 750);
DISPLAY INVISIBLE (425 750);
FORCEPROP 1 LASTPIN (225 675) $PN 1
R 1
J 0
(245 685);
DISPLAY 0.787234 (245 685);
PAINT ORANGE (245 685);
DISPLAY INVISIBLE (245 685);
FORCEPROP 1 LASTPIN (425 675) $PN 2
R 1
J 0
(445 685);
DISPLAY 0.787234 (445 685);
PAINT ORANGE (445 685);
DISPLAY INVISIBLE (445 685);
FORCEPROP 2 LAST CDS_LIB mstr_discrete
J 0
(325 675);
PAINT MONO (325 675);
DISPLAY INVISIBLE (325 675);
FORCEPROP 2 LAST ROOM VDDQ_KLM_PWR_VR
R 1
J 0
(175 725);
DISPLAY 1.361702 (175 725);
PAINT ORANGE (175 725);
DISPLAY INVISIBLE (175 725);
FORCEADD CAP..1
R 1
(325 425);
FORCEPROP 1 LAST TOLERANCE 10%
R 1
J 0
(375 475);
DISPLAY 0.617021 (375 475);
PAINT SKYBLUE (375 475);
FORCEPROP 1 LAST VALUE 1.0UF
R 1
J 0
(275 475);
DISPLAY 0.617021 (275 475);
PAINT SKYBLUE (275 475);
FORCEPROP 1 LAST PACK_TYPE 0402
R 1
J 0
(525 475);
DISPLAY 0.617021 (525 475);
PAINT SKYBLUE (525 475);
FORCEPROP 1 LAST PART_NUMBER D97712-011
R 1
J 0
(475 475);
DISPLAY 0.617021 (475 475);
PAINT BLUE (475 475);
FORCEPROP 1 LAST MATERIAL X6S
R 1
J 0
(425 475);
DISPLAY 0.617021 (425 475);
PAINT SKYBLUE (425 475);
FORCEPROP 1 LAST VOLTAGE 16V
R 1
J 0
(325 475);
DISPLAY 0.617021 (325 475);
PAINT SKYBLUE (325 475);
FORCEPROP 1 LAST LOCATION C25W6
R 1
J 0
(225 475);
DISPLAY 0.617021 (225 475);
PAINT AQUA (225 475);
FORCEPROP 1 LAST PATH I143
R 1
J 0
(175 475);
DISPLAY 0.978723 (175 475);
PAINT WHITE (175 475);
DISPLAY INVISIBLE (175 475);
FORCEPROP 0 LAST CDS_SEC 1
R 1
J 0
(425 500);
PAINT MONO (425 500);
DISPLAY INVISIBLE (425 500);
FORCEPROP 0 LAST $SEC 1
R 1
J 0
(425 500);
PAINT MONO (425 500);
DISPLAY INVISIBLE (425 500);
FORCEPROP 0 LAST CDS_LOCATION C25W6
R 1
J 0
(425 500);
PAINT MONO (425 500);
DISPLAY INVISIBLE (425 500);
FORCEPROP 1 LASTPIN (225 425) $PN 1
R 1
J 0
(245 435);
DISPLAY 0.787234 (245 435);
PAINT ORANGE (245 435);
DISPLAY INVISIBLE (245 435);
FORCEPROP 1 LASTPIN (425 425) $PN 2
R 1
J 0
(445 435);
DISPLAY 0.787234 (445 435);
PAINT ORANGE (445 435);
DISPLAY INVISIBLE (445 435);
FORCEPROP 2 LAST CDS_LIB mstr_discrete
J 0
(325 425);
PAINT MONO (325 425);
DISPLAY INVISIBLE (325 425);
FORCEPROP 2 LAST ROOM VDDQ_KLM_PWR_VR
R 1
J 0
(175 475);
DISPLAY 1.361702 (175 475);
PAINT ORANGE (175 475);
DISPLAY INVISIBLE (175 475);
FORCEADD LED..3
(-900 0);
FORCEPROP 1 LAST LOCATION DS9E1
J 0
(-1000 200);
DISPLAY 0.617021 (-1000 200);
PAINT AQUA (-1000 200);
FORCEPROP 1 LAST PART_NUMBER C97278-010
J 0
(-1000 -150);
DISPLAY 0.617021 (-1000 -150);
PAINT BLUE (-1000 -150);
FORCEPROP 2 LASTPIN (-800 0) $PN 1
J 0
(-790 -65);
DISPLAY 0.617021 (-790 -65);
PAINT ORANGE (-790 -65);
FORCEPROP 2 LASTPIN (-1000 0) $PN 2
J 2
(-1010 -65);
DISPLAY 0.617021 (-1010 -65);
PAINT ORANGE (-1010 -65);
FORCEPROP 1 LAST MATERIAL IC
J 0
(-1000 150);
DISPLAY 0.617021 (-1000 150);
PAINT SKYBLUE (-1000 150);
FORCEPROP 1 LAST COLOR GREEN
J 0
(-1000 100);
DISPLAY 0.617021 (-1000 100);
PAINT BLUE (-1000 100);
FORCEPROP 0 LAST CDS_SEC 1
J 0
(-1000 250);
PAINT MONO (-1000 250);
DISPLAY INVISIBLE (-1000 250);
FORCEPROP 2 LAST CDS_LIB mstr_discrete
J 0
(-900 0);
PAINT ORANGE (-900 0);
DISPLAY INVISIBLE (-900 0);
FORCEPROP 2 LAST SEC 1
J 0
(-1000 250);
DISPLAY 0.680851 (-1000 250);
PAINT MONO (-1000 250);
DISPLAY INVISIBLE (-1000 250);
FORCEPROP 2 LAST CDS_LOCATION DS9E1
J 0
(-1000 200);
DISPLAY 0.617021 (-1000 200);
PAINT AQUA (-1000 200);
DISPLAY INVISIBLE (-1000 200);
FORCEPROP 2 LAST ROOM BMC
J 0
(-1000 250);
DISPLAY 1.021277 (-1000 250);
PAINT ORANGE (-1000 250);
DISPLAY INVISIBLE (-1000 250);
FORCEPROP 1 LAST PACK_TYPE A1LF
J 0
(-1000 250);
DISPLAY 0.978723 (-1000 250);
PAINT SKYBLUE (-1000 250);
DISPLAY INVISIBLE (-1000 250);
FORCEPROP 2 LAST SEC_TYPE A1LF
J 0
(-1000 250);
DISPLAY 1.021277 (-1000 250);
PAINT ORANGE (-1000 250);
DISPLAY INVISIBLE (-1000 250);
FORCEPROP 2 LAST BOM_COST SM_CONTROLLER
J 0
(-1000 300);
DISPLAY 1.021277 (-1000 300);
PAINT ORANGE (-1000 300);
DISPLAY INVISIBLE (-1000 300);
FORCEPROP 1 LAST PATH I144
J 0
(-550 150);
DISPLAY 0.978723 (-550 150);
PAINT BLUE (-550 150);
DISPLAY INVISIBLE (-550 150);
FORCEADD FET_N_DUAL..5
(-1100 -375);
FORCEPROP 1 LASTPIN (-1100 -175) $PN 3
J 2
(-1047 -210);
DISPLAY 0.617021 (-1047 -210);
PAINT WHITE (-1047 -210);
FORCEPROP 1 LAST VALUE NTJD4001N
J 0
(-900 -425);
DISPLAY 0.617021 (-900 -425);
PAINT SKYBLUE (-900 -425);
FORCEPROP 1 LAST MATERIAL FET
J 0
(-900 -475);
DISPLAY 0.617021 (-900 -475);
PAINT SKYBLUE (-900 -475);
FORCEPROP 1 LAST PART_NUMBER E40049-001
J 0
(-900 -575);
DISPLAY 0.617021 (-900 -575);
PAINT BLUE (-900 -575);
FORCEPROP 1 LAST LOCATION Q9E1
J 0
(-900 -375);
DISPLAY 0.617021 (-900 -375);
PAINT AQUA (-900 -375);
FORCEPROP 1 LASTPIN (-1300 -475) $PN 5
J 2
(-1297 -460);
DISPLAY 0.617021 (-1297 -460);
PAINT WHITE (-1297 -460);
FORCEPROP 1 LASTPIN (-1100 -575) $PN 4
J 2
(-1042 -575);
DISPLAY 0.617021 (-1042 -575);
PAINT WHITE (-1042 -575);
FORCEPROP 0 LAST CDS_SEC 2
J 0
(-900 -325);
PAINT MONO (-900 -325);
DISPLAY INVISIBLE (-900 -325);
FORCEPROP 2 LAST CDS_LIB mstr_discrete
J 0
(-1100 -375);
PAINT MONO (-1100 -375);
DISPLAY INVISIBLE (-1100 -375);
FORCEPROP 1 LAST PACK_TYPE SMLF
J 0
(-900 -525);
DISPLAY 0.978723 (-900 -525);
PAINT SKYBLUE (-900 -525);
DISPLAY INVISIBLE (-900 -525);
FORCEPROP 2 LAST CDS_LOCATION Q9E1
J 0
(-900 -375);
DISPLAY 0.617021 (-900 -375);
PAINT AQUA (-900 -375);
DISPLAY INVISIBLE (-900 -375);
FORCEPROP 2 LAST SEC 2
J 0
(-900 -275);
DISPLAY 0.680851 (-900 -275);
PAINT MONO (-900 -275);
DISPLAY INVISIBLE (-900 -275);
FORCEPROP 2 LAST BOM_COST SM_CONTROLLER
J 0
(-900 -275);
DISPLAY 1.021277 (-900 -275);
PAINT ORANGE (-900 -275);
DISPLAY INVISIBLE (-900 -275);
FORCEPROP 2 LAST SEC_TYPE SMLF
J 0
(-900 -275);
DISPLAY 1.021277 (-900 -275);
PAINT ORANGE (-900 -275);
DISPLAY INVISIBLE (-900 -275);
FORCEPROP 2 LAST ROOM BMC
J 0
(-900 -325);
DISPLAY 1.021277 (-900 -325);
PAINT ORANGE (-900 -325);
DISPLAY INVISIBLE (-900 -325);
FORCEPROP 1 LAST PATH I145
J 0
(-900 -325);
DISPLAY 0.978723 (-900 -325);
PAINT BLUE (-900 -325);
DISPLAY INVISIBLE (-900 -325);
FORCEADD W_VCC_CIRCLE..1
(-150 -1350);
FORCEPROP 3 LASTPIN (-150 -1350) SIG_NAME P1V2_AUX_BMC\g
J 0
(-140 -1340);
DISPLAY 0.659574 (-140 -1340);
PAINT MONO (-140 -1340);
DISPLAY INVISIBLE (-140 -1340);
FORCEPROP 1 LAST HDL_POWER P1V2_AUX_BMC
J 1
(-129 -1275);
DISPLAY 0.872340 (-129 -1275);
PAINT ORANGE (-129 -1275);
FORCEPROP 1 LAST BODY_TYPE PLUMBING
J 0
(-138 -1356);
DISPLAY 0.340426 (-138 -1356);
PAINT GREEN (-138 -1356);
DISPLAY INVISIBLE (-138 -1356);
FORCEPROP 1 LAST CDS_LMAN_SYM_OUTLINE -100,100,100,-100
J 0
(-150 -1350);
DISPLAY 0.468085 (-150 -1350);
PAINT GREEN (-150 -1350);
DISPLAY INVISIBLE (-150 -1350);
FORCEPROP 2 LAST CDS_LIB w_power
J 0
(-150 -1350);
PAINT MONO (-150 -1350);
DISPLAY INVISIBLE (-150 -1350);
FORCEPROP 1 LAST PATH I146
J 0
(-150 -1350);
DISPLAY 0.617021 (-150 -1350);
PAINT GREEN (-150 -1350);
DISPLAY INVISIBLE (-150 -1350);
FORCEADD GND..1
(-150 -2150);
FORCEPROP 3 LASTPIN (-150 -2100) SIG_NAME GND\g
J 0
(-140 -2090);
DISPLAY 0.659574 (-140 -2090);
PAINT MONO (-140 -2090);
DISPLAY INVISIBLE (-140 -2090);
FORCEPROP 1 LAST HDL_POWER GND
J 0
(-150 -2000);
DISPLAY 0.872340 (-150 -2000);
PAINT GREEN (-150 -2000);
DISPLAY INVISIBLE (-150 -2000);
FORCEPROP 1 LAST BODY_TYPE PLUMBING
J 0
(-195 -2193);
DISPLAY 0.340426 (-195 -2193);
PAINT GREEN (-195 -2193);
DISPLAY INVISIBLE (-195 -2193);
FORCEPROP 2 LAST CDS_LIB mstr_symbols
J 0
(-150 -2150);
PAINT MONO (-150 -2150);
DISPLAY INVISIBLE (-150 -2150);
FORCEPROP 1 LAST SIZE 1B
J 0
(-75 -2200);
DISPLAY 0.872340 (-75 -2200);
PAINT AQUA (-75 -2200);
DISPLAY INVISIBLE (-75 -2200);
FORCEPROP 1 LAST VOLTAGE 0.0V
J 0
(-195 -2193);
DISPLAY 0.340426 (-195 -2193);
PAINT GREEN (-195 -2193);
DISPLAY INVISIBLE (-195 -2193);
FORCEPROP 1 LAST PATH I149
J 0
(-75 -2150);
DISPLAY 0.872340 (-75 -2150);
PAINT AQUA (-75 -2150);
DISPLAY INVISIBLE (-75 -2150);
FORCEADD GND..1
(-1100 -700);
FORCEPROP 3 LASTPIN (-1100 -650) SIG_NAME GND\g
J 0
(-1090 -640);
DISPLAY 0.659574 (-1090 -640);
PAINT MONO (-1090 -640);
DISPLAY INVISIBLE (-1090 -640);
FORCEPROP 1 LAST HDL_POWER GND
J 0
(-1100 -550);
DISPLAY 0.872340 (-1100 -550);
PAINT GREEN (-1100 -550);
DISPLAY INVISIBLE (-1100 -550);
FORCEPROP 1 LAST BODY_TYPE PLUMBING
J 0
(-1145 -743);
DISPLAY 0.340426 (-1145 -743);
PAINT GREEN (-1145 -743);
DISPLAY INVISIBLE (-1145 -743);
FORCEPROP 1 LAST VOLTAGE 0.0V
J 0
(-1145 -743);
DISPLAY 0.340426 (-1145 -743);
PAINT SKYBLUE (-1145 -743);
DISPLAY INVISIBLE (-1145 -743);
FORCEPROP 2 LAST CDS_LIB mstr_symbols
J 0
(-1100 -700);
PAINT ORANGE (-1100 -700);
DISPLAY INVISIBLE (-1100 -700);
FORCEPROP 1 LAST SIZE 1B
J 0
(-1025 -750);
DISPLAY 0.872340 (-1025 -750);
PAINT AQUA (-1025 -750);
DISPLAY INVISIBLE (-1025 -750);
FORCEPROP 1 LAST PATH I150
J 0
(-1025 -700);
DISPLAY 0.872340 (-1025 -700);
PAINT AQUA (-1025 -700);
DISPLAY INVISIBLE (-1025 -700);
FORCEADD P3V3_STBY..1
(-1700 -75);
FORCEPROP 3 LASTPIN (-1700 -125) SIG_NAME P3V3_STBY\g
J 0
(-1690 -115);
DISPLAY 0.659574 (-1690 -115);
PAINT MONO (-1690 -115);
DISPLAY INVISIBLE (-1690 -115);
FORCEPROP 1 LAST HDL_POWER P3V3_STBY
J 0
(-2000 -200);
DISPLAY 0.872340 (-2000 -200);
PAINT ORANGE (-2000 -200);
DISPLAY INVISIBLE (-2000 -200);
FORCEPROP 1 LAST BODY_TYPE PLUMBING
J 0
(-1745 -118);
DISPLAY 0.340426 (-1745 -118);
PAINT GREEN (-1745 -118);
DISPLAY INVISIBLE (-1745 -118);
FORCEPROP 1 LAST VOLTAGE 3.3V
J 0
(-1745 -118);
DISPLAY 0.340426 (-1745 -118);
PAINT SKYBLUE (-1745 -118);
DISPLAY INVISIBLE (-1745 -118);
FORCEPROP 1 LAST SIZE 1B
J 0
(-1655 -53);
DISPLAY 0.340426 (-1655 -53);
PAINT GREEN (-1655 -53);
DISPLAY INVISIBLE (-1655 -53);
FORCEPROP 2 LAST CDS_LIB mstr_symbols
J 0
(-1700 -75);
PAINT MONO (-1700 -75);
DISPLAY INVISIBLE (-1700 -75);
FORCEPROP 1 LAST PATH I172
J 0
(-1655 -73);
DISPLAY 0.340426 (-1655 -73);
PAINT GREEN (-1655 -73);
DISPLAY INVISIBLE (-1655 -73);
FORCEADD RES..2
(-1700 -300);
FORCEPROP 1 LAST PART_NUMBER G21796-072
J 0
(-1660 -425);
DISPLAY 0.617021 (-1660 -425);
PAINT BLUE (-1660 -425);
FORCEPROP 1 LAST VALUE 4.75K
J 0
(-1655 -225);
DISPLAY 0.617021 (-1655 -225);
PAINT SKYBLUE (-1655 -225);
FORCEPROP 1 LAST MATERIAL CHIP
J 0
(-1660 -375);
DISPLAY 0.617021 (-1660 -375);
PAINT SKYBLUE (-1660 -375);
FORCEPROP 1 LAST PACK_TYPE 0402
J 0
(-1660 -475);
DISPLAY 0.617021 (-1660 -475);
PAINT SKYBLUE (-1660 -475);
FORCEPROP 1 LASTPIN (-1700 -400) $PN 2
J 0
(-1695 -390);
DISPLAY 0.617021 (-1695 -390);
PAINT ORANGE (-1695 -390);
FORCEPROP 1 LASTPIN (-1700 -200) $PN 1
J 0
(-1695 -238);
DISPLAY 0.617021 (-1695 -238);
PAINT ORANGE (-1695 -238);
FORCEPROP 1 LAST TOLERANCE 1%
J 0
(-1655 -275);
DISPLAY 0.617021 (-1655 -275);
PAINT SKYBLUE (-1655 -275);
FORCEPROP 1 LAST LOCATION R9E21
J 0
(-1655 -175);
DISPLAY 0.617021 (-1655 -175);
PAINT AQUA (-1655 -175);
FORCEPROP 1 LAST WATTAGE 1/16W
J 0
(-1660 -325);
DISPLAY 0.617021 (-1660 -325);
PAINT SKYBLUE (-1660 -325);
FORCEPROP 0 LAST CDS_SEC 1
J 0
(-1650 -125);
PAINT MONO (-1650 -125);
DISPLAY INVISIBLE (-1650 -125);
FORCEPROP 2 LAST CDS_LIB mstr_discrete
J 0
(-1700 -300);
PAINT MONO (-1700 -300);
DISPLAY INVISIBLE (-1700 -300);
FORCEPROP 2 LAST CDS_LOCATION R9E21
J 0
(-1655 -175);
DISPLAY 0.617021 (-1655 -175);
PAINT AQUA (-1655 -175);
DISPLAY INVISIBLE (-1655 -175);
FORCEPROP 0 LAST ROOM BMC
J 0
(-1650 -75);
DISPLAY 1.021277 (-1650 -75);
PAINT ORANGE (-1650 -75);
DISPLAY INVISIBLE (-1650 -75);
FORCEPROP 2 LAST SEC 1
J 0
(-1650 -75);
DISPLAY 0.680851 (-1650 -75);
PAINT MONO (-1650 -75);
DISPLAY INVISIBLE (-1650 -75);
FORCEPROP 0 LAST BOM_COST SM_CONTROLLER
J 0
(-1650 25);
DISPLAY 1.021277 (-1650 25);
PAINT ORANGE (-1650 25);
DISPLAY INVISIBLE (-1650 25);
FORCEPROP 2 LAST SEC_TYPE 0402
J 0
(-1650 -75);
DISPLAY 1.021277 (-1650 -75);
PAINT ORANGE (-1650 -75);
DISPLAY INVISIBLE (-1650 -75);
FORCEPROP 1 LAST PATH I173
J 0
(-1650 -125);
DISPLAY 0.978723 (-1650 -125);
PAINT WHITE (-1650 -125);
DISPLAY INVISIBLE (-1650 -125);
FORCEADD P3V3_STBY..1
(-2175 -225);
FORCEPROP 3 LASTPIN (-2175 -275) SIG_NAME P3V3_STBY\g
J 0
(-2165 -265);
DISPLAY 0.659574 (-2165 -265);
PAINT MONO (-2165 -265);
DISPLAY INVISIBLE (-2165 -265);
FORCEPROP 1 LAST HDL_POWER P3V3_STBY
J 0
(-2475 -350);
DISPLAY 0.872340 (-2475 -350);
PAINT ORANGE (-2475 -350);
DISPLAY INVISIBLE (-2475 -350);
FORCEPROP 1 LAST BODY_TYPE PLUMBING
J 0
(-2220 -268);
DISPLAY 0.340426 (-2220 -268);
PAINT GREEN (-2220 -268);
DISPLAY INVISIBLE (-2220 -268);
FORCEPROP 1 LAST VOLTAGE 3.3V
J 0
(-2220 -268);
DISPLAY 0.340426 (-2220 -268);
PAINT SKYBLUE (-2220 -268);
DISPLAY INVISIBLE (-2220 -268);
FORCEPROP 2 LAST CDS_LIB mstr_symbols
J 0
(-2175 -225);
PAINT MONO (-2175 -225);
DISPLAY INVISIBLE (-2175 -225);
FORCEPROP 1 LAST SIZE 1B
J 0
(-2130 -203);
DISPLAY 0.340426 (-2130 -203);
PAINT GREEN (-2130 -203);
DISPLAY INVISIBLE (-2130 -203);
FORCEPROP 1 LAST PATH I174
J 0
(-2130 -223);
DISPLAY 0.340426 (-2130 -223);
PAINT GREEN (-2130 -223);
DISPLAY INVISIBLE (-2130 -223);
FORCEADD RES..2
(-2175 -475);
FORCEPROP 1 LAST LOCATION R8B25
J 0
(-2130 -350);
DISPLAY 0.617021 (-2130 -350);
PAINT AQUA (-2130 -350);
FORCEPROP 1 LASTPIN (-2175 -375) $PN 1
J 0
(-2170 -413);
DISPLAY 0.617021 (-2170 -413);
PAINT ORANGE (-2170 -413);
FORCEPROP 1 LAST MATERIAL CHIP
J 0
(-2135 -550);
DISPLAY 0.617021 (-2135 -550);
PAINT SKYBLUE (-2135 -550);
FORCEPROP 1 LAST TOLERANCE 1%
J 0
(-2130 -450);
DISPLAY 0.617021 (-2130 -450);
PAINT SKYBLUE (-2130 -450);
FORCEPROP 1 LAST PACK_TYPE 0402
J 0
(-2135 -650);
DISPLAY 0.617021 (-2135 -650);
PAINT SKYBLUE (-2135 -650);
FORCEPROP 1 LAST PART_NUMBER G21796-072
J 0
(-2135 -600);
DISPLAY 0.617021 (-2135 -600);
PAINT BLUE (-2135 -600);
FORCEPROP 1 LASTPIN (-2175 -575) $PN 2
J 0
(-2170 -565);
DISPLAY 0.617021 (-2170 -565);
PAINT ORANGE (-2170 -565);
FORCEPROP 1 LAST WATTAGE 1/16W
J 0
(-2135 -500);
DISPLAY 0.617021 (-2135 -500);
PAINT SKYBLUE (-2135 -500);
FORCEPROP 1 LAST VALUE 4.75K
J 0
(-2130 -400);
DISPLAY 0.617021 (-2130 -400);
PAINT SKYBLUE (-2130 -400);
FORCEPROP 0 LAST CDS_SEC 1
J 0
(-2125 -300);
PAINT MONO (-2125 -300);
DISPLAY INVISIBLE (-2125 -300);
FORCEPROP 2 LAST CDS_LIB mstr_discrete
J 0
(-2175 -475);
PAINT MONO (-2175 -475);
DISPLAY INVISIBLE (-2175 -475);
FORCEPROP 0 LAST BOM_COST SM_CONTROLLER
J 0
(-2125 -150);
DISPLAY 1.021277 (-2125 -150);
PAINT ORANGE (-2125 -150);
DISPLAY INVISIBLE (-2125 -150);
FORCEPROP 2 LAST SEC_TYPE 0402
J 0
(-2125 -250);
DISPLAY 1.021277 (-2125 -250);
PAINT ORANGE (-2125 -250);
DISPLAY INVISIBLE (-2125 -250);
FORCEPROP 2 LAST SEC 1
J 0
(-2125 -250);
DISPLAY 0.680851 (-2125 -250);
PAINT MONO (-2125 -250);
DISPLAY INVISIBLE (-2125 -250);
FORCEPROP 2 LAST CDS_LOCATION R8B25
J 0
(-2130 -350);
DISPLAY 0.617021 (-2130 -350);
PAINT AQUA (-2130 -350);
DISPLAY INVISIBLE (-2130 -350);
FORCEPROP 0 LAST ROOM BMC
J 0
(-2125 -250);
DISPLAY 1.021277 (-2125 -250);
PAINT ORANGE (-2125 -250);
DISPLAY INVISIBLE (-2125 -250);
FORCEPROP 1 LAST PATH I175
J 0
(-2125 -300);
DISPLAY 0.978723 (-2125 -300);
PAINT WHITE (-2125 -300);
DISPLAY INVISIBLE (-2125 -300);
FORCEADD GND..1
(-3400 325);
FORCEPROP 3 LASTPIN (-3400 375) SIG_NAME GND\g
J 0
(-3390 385);
DISPLAY 0.659574 (-3390 385);
PAINT MONO (-3390 385);
DISPLAY INVISIBLE (-3390 385);
FORCEPROP 1 LAST HDL_POWER GND
J 0
(-3400 475);
DISPLAY 0.872340 (-3400 475);
PAINT GREEN (-3400 475);
DISPLAY INVISIBLE (-3400 475);
FORCEPROP 1 LAST BODY_TYPE PLUMBING
J 0
(-3445 282);
DISPLAY 0.340426 (-3445 282);
PAINT GREEN (-3445 282);
DISPLAY INVISIBLE (-3445 282);
FORCEPROP 2 LAST CDS_LIB mstr_symbols
J 0
(-3400 325);
PAINT MONO (-3400 325);
DISPLAY INVISIBLE (-3400 325);
FORCEPROP 1 LAST VOLTAGE 0.0V
J 0
(-3445 282);
DISPLAY 0.340426 (-3445 282);
PAINT GREEN (-3445 282);
DISPLAY INVISIBLE (-3445 282);
FORCEPROP 1 LAST SIZE 1B
J 0
(-3325 275);
DISPLAY 0.872340 (-3325 275);
PAINT AQUA (-3325 275);
DISPLAY INVISIBLE (-3325 275);
FORCEPROP 1 LAST PATH I197
J 0
(-3325 325);
DISPLAY 0.872340 (-3325 325);
PAINT AQUA (-3325 325);
DISPLAY INVISIBLE (-3325 325);
FORCEADD FET_N_DUAL..5
(-1700 -800);
FORCEPROP 1 LAST PART_NUMBER E40049-001
J 0
(-1500 -1000);
DISPLAY 0.617021 (-1500 -1000);
PAINT BLUE (-1500 -1000);
FORCEPROP 1 LAST VALUE NTJD4001N
J 0
(-1500 -850);
DISPLAY 0.617021 (-1500 -850);
PAINT SKYBLUE (-1500 -850);
FORCEPROP 1 LAST LOCATION Q9E1
J 0
(-1500 -800);
DISPLAY 0.617021 (-1500 -800);
PAINT AQUA (-1500 -800);
FORCEPROP 1 LASTPIN (-1900 -900) $PN 2
J 2
(-1897 -885);
DISPLAY 0.617021 (-1897 -885);
PAINT WHITE (-1897 -885);
FORCEPROP 1 LASTPIN (-1700 -600) $PN 6
J 2
(-1647 -635);
DISPLAY 0.617021 (-1647 -635);
PAINT WHITE (-1647 -635);
FORCEPROP 1 LAST MATERIAL FET
J 0
(-1500 -900);
DISPLAY 0.617021 (-1500 -900);
PAINT SKYBLUE (-1500 -900);
FORCEPROP 1 LASTPIN (-1700 -1000) $PN 1
J 2
(-1642 -1000);
DISPLAY 0.617021 (-1642 -1000);
PAINT WHITE (-1642 -1000);
FORCEPROP 0 LAST CDS_SEC 1
J 0
(-1500 -750);
PAINT MONO (-1500 -750);
DISPLAY INVISIBLE (-1500 -750);
FORCEPROP 2 LAST CDS_LIB mstr_discrete
J 0
(-1700 -800);
PAINT MONO (-1700 -800);
DISPLAY INVISIBLE (-1700 -800);
FORCEPROP 2 LAST CDS_LOCATION Q9E1
J 0
(-1500 -800);
DISPLAY 0.617021 (-1500 -800);
PAINT AQUA (-1500 -800);
DISPLAY INVISIBLE (-1500 -800);
FORCEPROP 0 LAST ROOM BMC
J 0
(-1500 -700);
DISPLAY 1.021277 (-1500 -700);
PAINT ORANGE (-1500 -700);
DISPLAY INVISIBLE (-1500 -700);
FORCEPROP 1 LAST PACK_TYPE SMLF
J 0
(-1500 -950);
DISPLAY 0.978723 (-1500 -950);
PAINT SKYBLUE (-1500 -950);
DISPLAY INVISIBLE (-1500 -950);
FORCEPROP 2 LAST SEC_TYPE SMLF
J 0
(-1500 -700);
DISPLAY 1.021277 (-1500 -700);
PAINT ORANGE (-1500 -700);
DISPLAY INVISIBLE (-1500 -700);
FORCEPROP 2 LAST SEC 1
J 0
(-1500 -700);
DISPLAY 0.680851 (-1500 -700);
PAINT MONO (-1500 -700);
DISPLAY INVISIBLE (-1500 -700);
FORCEPROP 0 LAST BOM_COST SM_CONTROLLER
J 0
(-1500 -600);
DISPLAY 1.021277 (-1500 -600);
PAINT ORANGE (-1500 -600);
DISPLAY INVISIBLE (-1500 -600);
FORCEPROP 1 LAST PATH I198
J 0
(-1500 -750);
DISPLAY 0.978723 (-1500 -750);
PAINT BLUE (-1500 -750);
DISPLAY INVISIBLE (-1500 -750);
FORCEADD GND..1
(-1700 -1100);
FORCEPROP 3 LASTPIN (-1700 -1050) SIG_NAME GND\g
J 0
(-1690 -1040);
DISPLAY 0.659574 (-1690 -1040);
PAINT MONO (-1690 -1040);
DISPLAY INVISIBLE (-1690 -1040);
FORCEPROP 1 LAST HDL_POWER GND
J 0
(-1700 -950);
DISPLAY 0.872340 (-1700 -950);
PAINT GREEN (-1700 -950);
DISPLAY INVISIBLE (-1700 -950);
FORCEPROP 1 LAST BODY_TYPE PLUMBING
J 0
(-1745 -1143);
DISPLAY 0.340426 (-1745 -1143);
PAINT GREEN (-1745 -1143);
DISPLAY INVISIBLE (-1745 -1143);
FORCEPROP 1 LAST VOLTAGE 0.0V
J 0
(-1745 -1143);
DISPLAY 0.340426 (-1745 -1143);
PAINT SKYBLUE (-1745 -1143);
DISPLAY INVISIBLE (-1745 -1143);
FORCEPROP 1 LAST SIZE 1B
J 0
(-1625 -1150);
DISPLAY 0.872340 (-1625 -1150);
PAINT AQUA (-1625 -1150);
DISPLAY INVISIBLE (-1625 -1150);
FORCEPROP 2 LAST CDS_LIB mstr_symbols
J 0
(-1700 -1100);
PAINT MONO (-1700 -1100);
DISPLAY INVISIBLE (-1700 -1100);
FORCEPROP 1 LAST PATH I199
J 0
(-1625 -1100);
DISPLAY 0.872340 (-1625 -1100);
PAINT AQUA (-1625 -1100);
DISPLAY INVISIBLE (-1625 -1100);
FORCEADD W_VCC_CIRCLE..1
(-1675 -1250);
FORCEPROP 3 LASTPIN (-1675 -1250) SIG_NAME P1V2_AUX_BMC\g
J 0
(-1665 -1240);
DISPLAY 0.659574 (-1665 -1240);
PAINT MONO (-1665 -1240);
DISPLAY INVISIBLE (-1665 -1240);
FORCEPROP 1 LAST HDL_POWER P1V2_AUX_BMC
J 1
(-1779 -1175);
DISPLAY 0.872340 (-1779 -1175);
PAINT ORANGE (-1779 -1175);
FORCEPROP 1 LAST BODY_TYPE PLUMBING
J 0
(-1663 -1256);
DISPLAY 0.340426 (-1663 -1256);
PAINT GREEN (-1663 -1256);
DISPLAY INVISIBLE (-1663 -1256);
FORCEPROP 2 LAST CDS_LIB w_power
J 0
(-1675 -1250);
PAINT MONO (-1675 -1250);
DISPLAY INVISIBLE (-1675 -1250);
FORCEPROP 1 LAST CDS_LMAN_SYM_OUTLINE -100,100,100,-100
J 0
(-1675 -1250);
DISPLAY 0.468085 (-1675 -1250);
PAINT GREEN (-1675 -1250);
DISPLAY INVISIBLE (-1675 -1250);
FORCEPROP 1 LAST PATH I200
J 0
(-1675 -1250);
DISPLAY 0.617021 (-1675 -1250);
PAINT GREEN (-1675 -1250);
DISPLAY INVISIBLE (-1675 -1250);
FORCEADD RES..2
(-1675 -1575);
FORCEPROP 1 LAST PART_NUMBER G21796-026
J 0
(-1635 -1700);
DISPLAY 0.617021 (-1635 -1700);
PAINT BLUE (-1635 -1700);
FORCEPROP 1 LAST WATTAGE 1/16W
J 0
(-1635 -1600);
DISPLAY 0.617021 (-1635 -1600);
PAINT SKYBLUE (-1635 -1600);
FORCEPROP 1 LAST LOCATION R1T30
J 0
(-1630 -1450);
DISPLAY 0.617021 (-1630 -1450);
PAINT AQUA (-1630 -1450);
FORCEPROP 1 LASTPIN (-1675 -1475) $PN 1
J 0
(-1670 -1513);
DISPLAY 0.617021 (-1670 -1513);
PAINT ORANGE (-1670 -1513);
FORCEPROP 1 LAST TOLERANCE 1%
J 0
(-1630 -1550);
DISPLAY 0.617021 (-1630 -1550);
PAINT SKYBLUE (-1630 -1550);
FORCEPROP 1 LAST MATERIAL CHIP
J 0
(-1635 -1650);
DISPLAY 0.617021 (-1635 -1650);
PAINT SKYBLUE (-1635 -1650);
FORCEPROP 1 LAST PACK_TYPE 0402
J 0
(-1635 -1750);
DISPLAY 0.617021 (-1635 -1750);
PAINT SKYBLUE (-1635 -1750);
FORCEPROP 1 LAST VALUE 1.00K
J 0
(-1630 -1500);
DISPLAY 0.617021 (-1630 -1500);
PAINT SKYBLUE (-1630 -1500);
FORCEPROP 1 LASTPIN (-1675 -1675) $PN 2
J 0
(-1670 -1665);
DISPLAY 0.617021 (-1670 -1665);
PAINT ORANGE (-1670 -1665);
FORCEPROP 2 LAST SEC 1
J 0
(-1625 -1350);
DISPLAY 0.680851 (-1625 -1350);
PAINT MONO (-1625 -1350);
DISPLAY INVISIBLE (-1625 -1350);
FORCEPROP 2 LAST BOM_COST SM_MEM
J 0
(-1625 -1350);
DISPLAY 1.021277 (-1625 -1350);
PAINT ORANGE (-1625 -1350);
DISPLAY INVISIBLE (-1625 -1350);
FORCEPROP 2 LAST CDS_LIB mstr_discrete
J 0
(-1675 -1575);
PAINT ORANGE (-1675 -1575);
DISPLAY INVISIBLE (-1675 -1575);
FORCEPROP 2 LAST SEC_TYPE 0402
J 0
(-1625 -1350);
DISPLAY 1.021277 (-1625 -1350);
PAINT ORANGE (-1625 -1350);
DISPLAY INVISIBLE (-1625 -1350);
FORCEPROP 2 LAST ROOM BMC_MEMORY
J 0
(-1625 -1400);
DISPLAY 1.021277 (-1625 -1400);
PAINT ORANGE (-1625 -1400);
DISPLAY INVISIBLE (-1625 -1400);
FORCEPROP 0 LAST CDS_LOCATION R1T30
J 0
(-1625 -1400);
PAINT MONO (-1625 -1400);
DISPLAY INVISIBLE (-1625 -1400);
FORCEPROP 0 LAST CDS_SEC 1
J 0
(-1625 -1400);
PAINT MONO (-1625 -1400);
DISPLAY INVISIBLE (-1625 -1400);
FORCEPROP 1 LAST PATH I201
J 0
(-1625 -1400);
DISPLAY 0.978723 (-1625 -1400);
PAINT WHITE (-1625 -1400);
DISPLAY INVISIBLE (-1625 -1400);
FORCEADD RES..2
(-1675 -2000);
FORCEPROP 1 LAST WATTAGE 1/16W
J 0
(-1635 -2025);
DISPLAY 0.617021 (-1635 -2025);
PAINT SKYBLUE (-1635 -2025);
FORCEPROP 1 LAST PART_NUMBER G21796-026
J 0
(-1635 -2125);
DISPLAY 0.617021 (-1635 -2125);
PAINT BLUE (-1635 -2125);
FORCEPROP 1 LAST LOCATION R1T29
J 0
(-1630 -1875);
DISPLAY 0.617021 (-1630 -1875);
PAINT AQUA (-1630 -1875);
FORCEPROP 1 LAST VALUE 1.00K
J 0
(-1630 -1925);
DISPLAY 0.617021 (-1630 -1925);
PAINT SKYBLUE (-1630 -1925);
FORCEPROP 1 LAST TOLERANCE 1%
J 0
(-1630 -1975);
DISPLAY 0.617021 (-1630 -1975);
PAINT SKYBLUE (-1630 -1975);
FORCEPROP 1 LAST MATERIAL CHIP
J 0
(-1635 -2075);
DISPLAY 0.617021 (-1635 -2075);
PAINT SKYBLUE (-1635 -2075);
FORCEPROP 1 LAST PACK_TYPE 0402
J 0
(-1635 -2175);
DISPLAY 0.617021 (-1635 -2175);
PAINT SKYBLUE (-1635 -2175);
FORCEPROP 1 LASTPIN (-1675 -2100) $PN 2
J 0
(-1670 -2090);
DISPLAY 0.617021 (-1670 -2090);
PAINT ORANGE (-1670 -2090);
FORCEPROP 1 LASTPIN (-1675 -1900) $PN 1
J 0
(-1670 -1938);
DISPLAY 0.617021 (-1670 -1938);
PAINT ORANGE (-1670 -1938);
FORCEPROP 2 LAST SEC 1
J 0
(-1625 -1775);
DISPLAY 0.680851 (-1625 -1775);
PAINT MONO (-1625 -1775);
DISPLAY INVISIBLE (-1625 -1775);
FORCEPROP 2 LAST BOM_COST SM_MEM
J 0
(-1625 -1775);
DISPLAY 1.021277 (-1625 -1775);
PAINT ORANGE (-1625 -1775);
DISPLAY INVISIBLE (-1625 -1775);
FORCEPROP 2 LAST CDS_LIB mstr_discrete
J 0
(-1675 -2000);
PAINT ORANGE (-1675 -2000);
DISPLAY INVISIBLE (-1675 -2000);
FORCEPROP 2 LAST SEC_TYPE 0402
J 0
(-1625 -1775);
DISPLAY 1.021277 (-1625 -1775);
PAINT ORANGE (-1625 -1775);
DISPLAY INVISIBLE (-1625 -1775);
FORCEPROP 2 LAST ROOM BMC_MEMORY
J 0
(-1625 -1825);
DISPLAY 1.021277 (-1625 -1825);
PAINT ORANGE (-1625 -1825);
DISPLAY INVISIBLE (-1625 -1825);
FORCEPROP 0 LAST CDS_LOCATION R1T29
J 0
(-1625 -1825);
PAINT MONO (-1625 -1825);
DISPLAY INVISIBLE (-1625 -1825);
FORCEPROP 0 LAST CDS_SEC 1
J 0
(-1625 -1825);
PAINT MONO (-1625 -1825);
DISPLAY INVISIBLE (-1625 -1825);
FORCEPROP 1 LAST PATH I202
J 0
(-1625 -1825);
DISPLAY 0.978723 (-1625 -1825);
PAINT WHITE (-1625 -1825);
DISPLAY INVISIBLE (-1625 -1825);
FORCEADD GND..1
(-1675 -2450);
FORCEPROP 3 LASTPIN (-1675 -2400) SIG_NAME GND\g
J 0
(-1665 -2390);
DISPLAY 0.659574 (-1665 -2390);
PAINT MONO (-1665 -2390);
DISPLAY INVISIBLE (-1665 -2390);
FORCEPROP 1 LAST HDL_POWER GND
J 0
(-1675 -2300);
DISPLAY 0.872340 (-1675 -2300);
PAINT GREEN (-1675 -2300);
DISPLAY INVISIBLE (-1675 -2300);
FORCEPROP 1 LAST BODY_TYPE PLUMBING
J 0
(-1720 -2493);
DISPLAY 0.340426 (-1720 -2493);
PAINT GREEN (-1720 -2493);
DISPLAY INVISIBLE (-1720 -2493);
FORCEPROP 1 LAST VOLTAGE 0.0V
J 0
(-1720 -2493);
DISPLAY 0.340426 (-1720 -2493);
PAINT GREEN (-1720 -2493);
DISPLAY INVISIBLE (-1720 -2493);
FORCEPROP 1 LAST SIZE 1B
J 0
(-1600 -2500);
DISPLAY 0.872340 (-1600 -2500);
PAINT AQUA (-1600 -2500);
DISPLAY INVISIBLE (-1600 -2500);
FORCEPROP 2 LAST CDS_LIB mstr_symbols
J 0
(-1675 -2450);
PAINT ORANGE (-1675 -2450);
DISPLAY INVISIBLE (-1675 -2450);
FORCEPROP 1 LAST PATH I204
J 0
(-1600 -2450);
DISPLAY 0.872340 (-1600 -2450);
PAINT AQUA (-1600 -2450);
DISPLAY INVISIBLE (-1600 -2450);
FORCEADD OFFPAGE..1
(-2950 -900);
FORCEPROP 2 LAST $XR1 146 
J 0
(-3352 -900);
DISPLAY 0.638298 (-3352 -900);
PAINT MONO (-3352 -900);
FORCEPROP 2 LAST $XR0 119 
J 0
(-3232 -900);
DISPLAY 0.638298 (-3232 -900);
PAINT MONO (-3232 -900);
FORCEPROP 1 LAST COMMENT_BODY TRUE
J 0
(-2825 -1000);
DISPLAY 0.872340 (-2825 -1000);
PAINT GREEN (-2825 -1000);
DISPLAY INVISIBLE (-2825 -1000);
FORCEPROP 1 LAST OFFPAGE TRUE
J 0
(-2625 -1025);
DISPLAY 0.872340 (-2625 -1025);
PAINT GREEN (-2625 -1025);
DISPLAY INVISIBLE (-2625 -1025);
FORCEPROP 2 LAST PATH I207
J 0
(-3200 -850);
DISPLAY 1.021277 (-3200 -850);
PAINT ORANGE (-3200 -850);
DISPLAY INVISIBLE (-3200 -850);
FORCEPROP 2 LAST CDS_LIB mstr_standard
J 0
(-2950 -900);
PAINT MONO (-2950 -900);
DISPLAY INVISIBLE (-2950 -900);
FORCEADD OFFPAGE..2
R 2
(500 150);
FORCEPROP 2 LAST $XR1 151 
J 0
(95 150);
DISPLAY 0.638298 (95 150);
PAINT MONO (95 150);
FORCEPROP 2 LAST $XR0 143 
J 0
(215 150);
DISPLAY 0.638298 (215 150);
PAINT MONO (215 150);
FORCEPROP 1 LAST COMMENT_BODY TRUE
J 2
(545 55);
DISPLAY 0.872340 (545 55);
PAINT GREEN (545 55);
DISPLAY INVISIBLE (545 55);
FORCEPROP 1 LAST OFFPAGE TRUE
J 2
(175 25);
DISPLAY 0.872340 (175 25);
PAINT GREEN (175 25);
DISPLAY INVISIBLE (175 25);
FORCEPROP 2 LAST CDS_LIB mstr_standard
J 0
(500 150);
PAINT MONO (500 150);
DISPLAY INVISIBLE (500 150);
FORCEPROP 2 LAST PATH I208
J 0
(550 225);
DISPLAY 1.021277 (550 225);
PAINT ORANGE (550 225);
DISPLAY INVISIBLE (550 225);
FORCEADD RES..2
R 1
(3125 1975);
FORCEPROP 1 LAST PART_NUMBER G21796-074
J 0
(3050 2165);
DISPLAY 0.617021 (3050 2165);
PAINT BLUE (3050 2165);
FORCEPROP 1 LASTPIN (3025 1975) $PN 1
J 0
(3038 1980);
DISPLAY 0.617021 (3038 1980);
PAINT ORANGE (3038 1980);
FORCEPROP 1 LASTPIN (3225 1975) $PN 2
J 0
(3190 1980);
DISPLAY 0.617021 (3190 1980);
PAINT ORANGE (3190 1980);
FORCEPROP 1 LAST LOCATION R9F34
J 0
(3050 2120);
DISPLAY 0.617021 (3050 2120);
PAINT AQUA (3050 2120);
FORCEPROP 1 LAST MATERIAL EMPTY
J 0
(3150 1790);
DISPLAY 0.617021 (3150 1790);
PAINT RED (3150 1790);
FORCEPROP 1 LAST VALUE 33.2
J 0
(3050 1845);
DISPLAY 0.617021 (3050 1845);
PAINT SKYBLUE (3050 1845);
FORCEPROP 1 LAST PACK_TYPE 0402
J 0
(3300 1790);
DISPLAY 0.617021 (3300 1790);
PAINT SKYBLUE (3300 1790);
FORCEPROP 1 LAST WATTAGE 1/16W
J 0
(3025 1790);
DISPLAY 0.617021 (3025 1790);
PAINT SKYBLUE (3025 1790);
FORCEPROP 1 LAST TOLERANCE 1%
J 0
(3150 1845);
DISPLAY 0.617021 (3150 1845);
PAINT SKYBLUE (3150 1845);
FORCEPROP 2 LAST CDS_LOCATION R9F34
R 1
J 0
(3000 2020);
DISPLAY 0.617021 (3000 2020);
PAINT AQUA (3000 2020);
DISPLAY INVISIBLE (3000 2020);
FORCEPROP 2 LAST CDS_LIB mstr_discrete
R 1
J 0
(3125 1975);
PAINT ORANGE (3125 1975);
DISPLAY INVISIBLE (3125 1975);
FORCEPROP 0 LAST ROOM DEBUG
R 1
J 0
(2900 2025);
DISPLAY 1.021277 (2900 2025);
PAINT ORANGE (2900 2025);
DISPLAY INVISIBLE (2900 2025);
FORCEPROP 2 LAST SEC_TYPE 0402
R 1
J 0
(2900 2025);
DISPLAY 1.021277 (2900 2025);
PAINT ORANGE (2900 2025);
DISPLAY INVISIBLE (2900 2025);
FORCEPROP 2 LAST SEC 1
R 1
J 0
(2900 2025);
DISPLAY 0.680851 (2900 2025);
PAINT MONO (2900 2025);
DISPLAY INVISIBLE (2900 2025);
FORCEPROP 1 LAST PATH I209
R 1
J 0
(2950 2025);
DISPLAY 0.978723 (2950 2025);
PAINT WHITE (2950 2025);
DISPLAY INVISIBLE (2950 2025);
FORCEADD RES..2
R 2
(-150 -1500);
FORCEPROP 1 LASTPIN (-150 -1600) $PN 2
J 2
(-155 -1590);
DISPLAY 0.787234 (-155 -1590);
PAINT ORANGE (-155 -1590);
FORCEPROP 1 LAST TOLERANCE 1%
J 2
(-195 -1525);
DISPLAY 0.617021 (-195 -1525);
PAINT SKYBLUE (-195 -1525);
FORCEPROP 1 LASTPIN (-150 -1400) $PN 1
J 2
(-155 -1438);
DISPLAY 0.787234 (-155 -1438);
PAINT ORANGE (-155 -1438);
FORCEPROP 1 LAST PACK_TYPE 0402
J 2
(-190 -1675);
DISPLAY 0.617021 (-190 -1675);
PAINT SKYBLUE (-190 -1675);
FORCEPROP 1 LAST PART_NUMBER G21796-072
J 2
(-190 -1625);
DISPLAY 0.617021 (-190 -1625);
PAINT BLUE (-190 -1625);
FORCEPROP 1 LAST WATTAGE 1/16W
J 2
(-190 -1575);
DISPLAY 0.617021 (-190 -1575);
PAINT SKYBLUE (-190 -1575);
FORCEPROP 1 LAST MATERIAL EMPTY
J 2
(-190 -1475);
DISPLAY 0.617021 (-190 -1475);
PAINT RED (-190 -1475);
FORCEPROP 1 LAST VALUE 4.75K
J 2
(-195 -1425);
DISPLAY 0.617021 (-195 -1425);
PAINT SKYBLUE (-195 -1425);
FORCEPROP 1 LAST LOCATION R25W119
J 2
(-195 -1375);
DISPLAY 0.617021 (-195 -1375);
PAINT AQUA (-195 -1375);
FORCEPROP 0 LAST CDS_LOCATION R25W119
J 0
(-175 -1325);
PAINT MONO (-175 -1325);
DISPLAY INVISIBLE (-175 -1325);
FORCEPROP 2 LAST SEC_TYPE 0402
J 0
(-200 -1275);
DISPLAY 1.021277 (-200 -1275);
PAINT ORANGE (-200 -1275);
DISPLAY INVISIBLE (-200 -1275);
FORCEPROP 0 LAST SEC 1
J 0
(-175 -1325);
PAINT MONO (-175 -1325);
DISPLAY INVISIBLE (-175 -1325);
FORCEPROP 2 LAST CDS_LIB mstr_discrete
J 0
(-150 -1500);
PAINT MONO (-150 -1500);
DISPLAY INVISIBLE (-150 -1500);
FORCEPROP 2 LAST ROOM SB_SPI
J 0
(-175 -1325);
DISPLAY 1.021277 (-175 -1325);
PAINT ORANGE (-175 -1325);
DISPLAY INVISIBLE (-175 -1325);
FORCEPROP 2 LAST BOM_COST MIO_BIOS_MEM
J 0
(-175 -1275);
DISPLAY 1.021277 (-175 -1275);
PAINT ORANGE (-175 -1275);
DISPLAY INVISIBLE (-175 -1275);
FORCEPROP 2 LAST NO_XNET_CONNECTION 1
J 0
(-200 -1275);
PAINT MONO (-200 -1275);
DISPLAY INVISIBLE (-200 -1275);
FORCEPROP 1 LAST PATH I210
J 2
(-200 -1325);
DISPLAY 0.978723 (-200 -1325);
PAINT WHITE (-200 -1325);
DISPLAY INVISIBLE (-200 -1325);
FORCEADD RES..1
R 5
(-150 -1950);
FORCEPROP 1 LAST LOCATION R25W118
J 0
(-100 -1825);
DISPLAY 0.617021 (-100 -1825);
PAINT AQUA (-100 -1825);
FORCEPROP 1 LAST PART_NUMBER G21497-005
J 0
(-100 -2075);
DISPLAY 0.617021 (-100 -2075);
PAINT BLUE (-100 -2075);
FORCEPROP 1 LASTPIN (-150 -2050) $PN 2
J 0
(-138 -2062);
DISPLAY 0.787234 (-138 -2062);
PAINT ORANGE (-138 -2062);
FORCEPROP 1 LAST WATTAGE 1/16W
J 0
(-100 -1975);
DISPLAY 0.617021 (-100 -1975);
PAINT SKYBLUE (-100 -1975);
FORCEPROP 1 LAST VALUE 0.0
J 0
(-100 -1875);
DISPLAY 0.617021 (-100 -1875);
PAINT SKYBLUE (-100 -1875);
FORCEPROP 1 LASTPIN (-150 -1850) $PN 1
J 0
(-138 -1862);
DISPLAY 0.787234 (-138 -1862);
PAINT ORANGE (-138 -1862);
FORCEPROP 1 LAST MATERIAL CHIP
J 0
(-100 -2025);
DISPLAY 0.617021 (-100 -2025);
PAINT SKYBLUE (-100 -2025);
FORCEPROP 1 LAST TOLERANCE 5%
J 0
(-100 -1925);
DISPLAY 0.617021 (-100 -1925);
PAINT SKYBLUE (-100 -1925);
FORCEPROP 1 LAST PACK_TYPE 0402
J 0
(-100 -2125);
DISPLAY 0.617021 (-100 -2125);
PAINT SKYBLUE (-100 -2125);
FORCEPROP 2 LAST CDS_LOCATION R25W118
R 3
J 0
(-100 -1900);
DISPLAY 0.617021 (-100 -1900);
PAINT AQUA (-100 -1900);
DISPLAY INVISIBLE (-100 -1900);
FORCEPROP 2 LAST SEC 1
R 3
J 0
(50 -1900);
DISPLAY 0.680851 (50 -1900);
PAINT MONO (50 -1900);
DISPLAY INVISIBLE (50 -1900);
FORCEPROP 2 LAST SEC_TYPE 0402
R 3
J 0
(50 -1900);
DISPLAY 1.021277 (50 -1900);
PAINT ORANGE (50 -1900);
DISPLAY INVISIBLE (50 -1900);
FORCEPROP 1 LAST PATH I211
R 3
J 0
(0 -1900);
DISPLAY 0.978723 (0 -1900);
PAINT WHITE (0 -1900);
DISPLAY INVISIBLE (0 -1900);
FORCEPROP 2 LAST CDS_LIB mstr_discrete
R 3
J 0
(-150 -1950);
PAINT ORANGE (-150 -1950);
DISPLAY INVISIBLE (-150 -1950);
FORCEPROP 0 LAST ROOM HOT_SWAP
R 3
J 0
(0 -1900);
DISPLAY 1.021277 (0 -1900);
PAINT ORANGE (0 -1900);
DISPLAY INVISIBLE (0 -1900);
FORCEADD CAP_A..1
(-1950 -2000);
FORCEPROP 1 LAST PART_NUMBER D97712-004
J 0
(-1900 -2150);
DISPLAY 0.617021 (-1900 -2150);
PAINT BLUE (-1900 -2150);
FORCEPROP 1 LAST VOLTAGE 6.3V
J 0
(-1900 -2000);
DISPLAY 0.617021 (-1900 -2000);
PAINT SKYBLUE (-1900 -2000);
FORCEPROP 1 LAST VALUE 1.0UF
J 0
(-1900 -1950);
DISPLAY 0.617021 (-1900 -1950);
PAINT SKYBLUE (-1900 -1950);
FORCEPROP 1 LAST PACK_TYPE 0402V
J 0
(-1900 -2200);
DISPLAY 0.617021 (-1900 -2200);
PAINT SKYBLUE (-1900 -2200);
FORCEPROP 1 LAST TOLERANCE 10%
J 0
(-1900 -2050);
DISPLAY 0.617021 (-1900 -2050);
PAINT SKYBLUE (-1900 -2050);
FORCEPROP 1 LAST MATERIAL X6S
J 0
(-1900 -2100);
DISPLAY 0.617021 (-1900 -2100);
PAINT SKYBLUE (-1900 -2100);
FORCEPROP 1 LASTPIN (-1950 -2100) $PN 2
J 0
(-1940 -2120);
DISPLAY 0.617021 (-1940 -2120);
PAINT ORANGE (-1940 -2120);
FORCEPROP 1 LASTPIN (-1950 -1900) $PN 1
J 0
(-1940 -1920);
DISPLAY 0.617021 (-1940 -1920);
PAINT ORANGE (-1940 -1920);
FORCEPROP 1 LAST LOCATION C25W12
J 0
(-1900 -1900);
DISPLAY 0.617021 (-1900 -1900);
PAINT AQUA (-1900 -1900);
FORCEPROP 2 LAST CDS_LOCATION C25W12
J 0
(-1900 -1900);
DISPLAY 0.617021 (-1900 -1900);
PAINT AQUA (-1900 -1900);
DISPLAY INVISIBLE (-1900 -1900);
FORCEPROP 2 LAST ROOM VDDQ_KLM_PWR_VR
J 0
(-1900 -1850);
DISPLAY 1.361702 (-1900 -1850);
PAINT ORANGE (-1900 -1850);
DISPLAY INVISIBLE (-1900 -1850);
FORCEPROP 2 LAST SEC 1
J 0
(-1900 -1800);
DISPLAY 0.680851 (-1900 -1800);
PAINT MONO (-1900 -1800);
DISPLAY INVISIBLE (-1900 -1800);
FORCEPROP 2 LAST SEC_TYPE 0402V
J 0
(-1900 -1800);
DISPLAY 1.021277 (-1900 -1800);
PAINT ORANGE (-1900 -1800);
DISPLAY INVISIBLE (-1900 -1800);
FORCEPROP 2 LAST CDS_SEC 1
J 0
(-1900 -1850);
PAINT ORANGE (-1900 -1850);
DISPLAY INVISIBLE (-1900 -1850);
FORCEPROP 2 LAST CDS_LIB dev_discrete
J 0
(-1950 -2000);
PAINT ORANGE (-1950 -2000);
DISPLAY INVISIBLE (-1950 -2000);
FORCEPROP 1 LAST PATH I212
J 0
(-1900 -1850);
DISPLAY 0.978723 (-1900 -1850);
PAINT WHITE (-1900 -1850);
DISPLAY INVISIBLE (-1900 -1850);
FORCEADD CAP_A..1
R 2
(-2275 -1600);
FORCEPROP 1 LAST TOLERANCE 10%
J 2
(-2325 -1575);
DISPLAY 0.617021 (-2325 -1575);
PAINT SKYBLUE (-2325 -1575);
FORCEPROP 1 LAST VOLTAGE 25V
J 2
(-2325 -1525);
DISPLAY 0.617021 (-2325 -1525);
PAINT SKYBLUE (-2325 -1525);
FORCEPROP 1 LASTPIN (-2275 -1500) $PN 1
J 2
(-2285 -1520);
DISPLAY 0.617021 (-2285 -1520);
PAINT ORANGE (-2285 -1520);
FORCEPROP 0 LAST POP NOPOP
J 0
(-2225 -1525);
DISPLAY 0.638298 (-2225 -1525);
PAINT RED (-2225 -1525);
FORCEPROP 1 LAST MATERIAL X7R
J 2
(-2325 -1625);
DISPLAY 0.617021 (-2325 -1625);
PAINT SKYBLUE (-2325 -1625);
FORCEPROP 1 LAST PART_NUMBER A36096-045
J 2
(-2325 -1675);
DISPLAY 0.617021 (-2325 -1675);
PAINT BLUE (-2325 -1675);
FORCEPROP 1 LASTPIN (-2275 -1700) $PN 2
J 2
(-2285 -1720);
DISPLAY 0.617021 (-2285 -1720);
PAINT ORANGE (-2285 -1720);
FORCEPROP 1 LAST PACK_TYPE 0402V
J 2
(-2325 -1725);
DISPLAY 0.617021 (-2325 -1725);
PAINT SKYBLUE (-2325 -1725);
FORCEPROP 1 LAST VALUE 0.01UF
J 2
(-2325 -1475);
DISPLAY 0.617021 (-2325 -1475);
PAINT SKYBLUE (-2325 -1475);
FORCEPROP 1 LAST LOCATION C25W10
J 2
(-2325 -1425);
DISPLAY 0.617021 (-2325 -1425);
PAINT AQUA (-2325 -1425);
FORCEPROP 2 LAST CDS_LOCATION C25W10
J 2
(-2325 -1500);
DISPLAY 0.617021 (-2325 -1500);
PAINT AQUA (-2325 -1500);
DISPLAY INVISIBLE (-2325 -1500);
FORCEPROP 1 LAST PATH I213
J 2
(-2325 -1450);
DISPLAY 0.978723 (-2325 -1450);
PAINT WHITE (-2325 -1450);
DISPLAY INVISIBLE (-2325 -1450);
FORCEPROP 2 LAST ROOM DDR4_CH_M
J 0
(-2275 -1600);
PAINT ORANGE (-2275 -1600);
DISPLAY INVISIBLE (-2275 -1600);
FORCEPROP 2 LAST SEC 1
J 0
(-2325 -1400);
PAINT MONO (-2325 -1400);
DISPLAY INVISIBLE (-2325 -1400);
FORCEPROP 2 LAST SEC_TYPE 0402V
J 0
(-2325 -1400);
DISPLAY 1.021277 (-2325 -1400);
PAINT ORANGE (-2325 -1400);
DISPLAY INVISIBLE (-2325 -1400);
FORCEPROP 2 LAST CDS_SEC 1
J 0
(-2325 -1450);
PAINT ORANGE (-2325 -1450);
DISPLAY INVISIBLE (-2325 -1450);
FORCEPROP 2 LAST CDS_LIB dev_discrete
J 0
(-2275 -1600);
PAINT ORANGE (-2275 -1600);
DISPLAY INVISIBLE (-2275 -1600);
FORCEPROP 2 LAST BOM_COST MEM
J 0
(-2275 -1600);
PAINT ORANGE (-2275 -1600);
DISPLAY INVISIBLE (-2275 -1600);
FORCEADD CAP_A..1
R 2
(-2275 -2000);
FORCEPROP 1 LAST VOLTAGE 25V
J 2
(-2325 -2000);
DISPLAY 0.617021 (-2325 -2000);
PAINT SKYBLUE (-2325 -2000);
FORCEPROP 1 LAST LOCATION C25W11
J 2
(-2325 -1900);
DISPLAY 0.617021 (-2325 -1900);
PAINT AQUA (-2325 -1900);
FORCEPROP 1 LAST PART_NUMBER A36096-045
J 2
(-2325 -2150);
DISPLAY 0.617021 (-2325 -2150);
PAINT BLUE (-2325 -2150);
FORCEPROP 1 LAST VALUE 0.01UF
J 2
(-2325 -1950);
DISPLAY 0.617021 (-2325 -1950);
PAINT SKYBLUE (-2325 -1950);
FORCEPROP 1 LAST TOLERANCE 10%
J 2
(-2325 -2050);
DISPLAY 0.617021 (-2325 -2050);
PAINT SKYBLUE (-2325 -2050);
FORCEPROP 1 LAST PACK_TYPE 0402V
J 2
(-2325 -2200);
DISPLAY 0.617021 (-2325 -2200);
PAINT SKYBLUE (-2325 -2200);
FORCEPROP 1 LAST MATERIAL X7R
J 2
(-2325 -2100);
DISPLAY 0.617021 (-2325 -2100);
PAINT SKYBLUE (-2325 -2100);
FORCEPROP 1 LASTPIN (-2275 -1900) $PN 1
J 2
(-2285 -1920);
DISPLAY 0.617021 (-2285 -1920);
PAINT ORANGE (-2285 -1920);
FORCEPROP 1 LASTPIN (-2275 -2100) $PN 2
J 2
(-2285 -2120);
DISPLAY 0.617021 (-2285 -2120);
PAINT ORANGE (-2285 -2120);
FORCEPROP 2 LAST CDS_LOCATION C25W11
J 2
(-2325 -1900);
DISPLAY 0.617021 (-2325 -1900);
PAINT AQUA (-2325 -1900);
DISPLAY INVISIBLE (-2325 -1900);
FORCEPROP 2 LAST BOM_COST MEM
J 0
(-2275 -2000);
PAINT ORANGE (-2275 -2000);
DISPLAY INVISIBLE (-2275 -2000);
FORCEPROP 2 LAST CDS_LIB dev_discrete
J 0
(-2275 -2000);
PAINT ORANGE (-2275 -2000);
DISPLAY INVISIBLE (-2275 -2000);
FORCEPROP 2 LAST CDS_SEC 1
J 0
(-2325 -1850);
PAINT ORANGE (-2325 -1850);
DISPLAY INVISIBLE (-2325 -1850);
FORCEPROP 2 LAST SEC_TYPE 0402V
J 0
(-2325 -1800);
DISPLAY 1.021277 (-2325 -1800);
PAINT ORANGE (-2325 -1800);
DISPLAY INVISIBLE (-2325 -1800);
FORCEPROP 2 LAST SEC 1
J 0
(-2325 -1800);
PAINT MONO (-2325 -1800);
DISPLAY INVISIBLE (-2325 -1800);
FORCEPROP 2 LAST ROOM DDR4_CH_M
J 0
(-2275 -2000);
PAINT ORANGE (-2275 -2000);
DISPLAY INVISIBLE (-2275 -2000);
FORCEPROP 1 LAST PATH I214
J 2
(-2325 -1850);
DISPLAY 0.978723 (-2325 -1850);
PAINT WHITE (-2325 -1850);
DISPLAY INVISIBLE (-2325 -1850);
FORCEADD CAP_A..1
(1100 550);
FORCEPROP 1 LAST TOLERANCE 10%
J 0
(1150 500);
DISPLAY 0.617021 (1150 500);
PAINT SKYBLUE (1150 500);
FORCEPROP 1 LAST LOCATION C25W14
J 0
(1150 650);
DISPLAY 0.617021 (1150 650);
PAINT AQUA (1150 650);
FORCEPROP 1 LAST VALUE 0.1UF
J 0
(1150 600);
DISPLAY 0.617021 (1150 600);
PAINT SKYBLUE (1150 600);
FORCEPROP 1 LAST PART_NUMBER A36096-030
J 0
(1150 400);
DISPLAY 0.617021 (1150 400);
PAINT BLUE (1150 400);
FORCEPROP 1 LAST VOLTAGE 16V
J 0
(1150 550);
DISPLAY 0.617021 (1150 550);
PAINT SKYBLUE (1150 550);
FORCEPROP 1 LASTPIN (1100 450) $PN 2
J 0
(1110 430);
DISPLAY 0.617021 (1110 430);
PAINT ORANGE (1110 430);
FORCEPROP 1 LASTPIN (1100 650) $PN 1
J 0
(1110 630);
DISPLAY 0.617021 (1110 630);
PAINT ORANGE (1110 630);
FORCEPROP 1 LAST PACK_TYPE 0402V
J 0
(1150 350);
DISPLAY 0.617021 (1150 350);
PAINT SKYBLUE (1150 350);
FORCEPROP 1 LAST MATERIAL X7R
J 0
(1150 450);
DISPLAY 0.617021 (1150 450);
PAINT SKYBLUE (1150 450);
FORCEPROP 2 LAST CDS_LOCATION C25W14
J 0
(1150 650);
DISPLAY 0.617021 (1150 650);
PAINT AQUA (1150 650);
DISPLAY INVISIBLE (1150 650);
FORCEPROP 1 LAST PATH I215
J 0
(1150 700);
DISPLAY 0.978723 (1150 700);
PAINT WHITE (1150 700);
DISPLAY INVISIBLE (1150 700);
FORCEPROP 2 LAST CDS_LIB dev_discrete
J 0
(1100 550);
PAINT ORANGE (1100 550);
DISPLAY INVISIBLE (1100 550);
FORCEPROP 2 LAST CDS_SEC 1
J 0
(1150 700);
PAINT ORANGE (1150 700);
DISPLAY INVISIBLE (1150 700);
FORCEPROP 2 LAST ROOM VDDQ_KLM_PWR_VR
J 0
(1150 700);
DISPLAY 1.361702 (1150 700);
PAINT ORANGE (1150 700);
DISPLAY INVISIBLE (1150 700);
FORCEPROP 2 LAST SEC_TYPE 0402V
J 0
(1150 775);
DISPLAY 1.021277 (1150 775);
PAINT ORANGE (1150 775);
DISPLAY INVISIBLE (1150 775);
FORCEPROP 2 LAST SEC 1
J 0
(1150 775);
DISPLAY 0.680851 (1150 775);
PAINT MONO (1150 775);
DISPLAY INVISIBLE (1150 775);
FORCEADD CAP_A..1
(1450 550);
FORCEPROP 1 LASTPIN (1450 450) $PN 2
J 0
(1460 430);
DISPLAY 0.617021 (1460 430);
PAINT ORANGE (1460 430);
FORCEPROP 1 LAST PACK_TYPE 0402V
J 0
(1500 350);
DISPLAY 0.617021 (1500 350);
PAINT SKYBLUE (1500 350);
FORCEPROP 1 LASTPIN (1450 650) $PN 1
J 0
(1460 630);
DISPLAY 0.617021 (1460 630);
PAINT ORANGE (1460 630);
FORCEPROP 1 LAST VALUE 0.1UF
J 0
(1500 600);
DISPLAY 0.617021 (1500 600);
PAINT SKYBLUE (1500 600);
FORCEPROP 1 LAST VOLTAGE 16V
J 0
(1500 550);
DISPLAY 0.617021 (1500 550);
PAINT SKYBLUE (1500 550);
FORCEPROP 1 LAST TOLERANCE 10%
J 0
(1500 500);
DISPLAY 0.617021 (1500 500);
PAINT SKYBLUE (1500 500);
FORCEPROP 1 LAST MATERIAL X7R
J 0
(1500 450);
DISPLAY 0.617021 (1500 450);
PAINT SKYBLUE (1500 450);
FORCEPROP 1 LAST PART_NUMBER A36096-030
J 0
(1500 400);
DISPLAY 0.617021 (1500 400);
PAINT BLUE (1500 400);
FORCEPROP 1 LAST LOCATION C25W15
J 0
(1500 650);
DISPLAY 0.617021 (1500 650);
PAINT AQUA (1500 650);
FORCEPROP 2 LAST CDS_LOCATION C25W15
J 0
(1500 650);
DISPLAY 0.617021 (1500 650);
PAINT AQUA (1500 650);
DISPLAY INVISIBLE (1500 650);
FORCEPROP 1 LAST PATH I216
J 0
(1500 700);
DISPLAY 0.978723 (1500 700);
PAINT WHITE (1500 700);
DISPLAY INVISIBLE (1500 700);
FORCEPROP 2 LAST CDS_LIB dev_discrete
J 0
(1450 550);
PAINT ORANGE (1450 550);
DISPLAY INVISIBLE (1450 550);
FORCEPROP 2 LAST CDS_SEC 1
J 0
(1500 700);
PAINT ORANGE (1500 700);
DISPLAY INVISIBLE (1500 700);
FORCEPROP 2 LAST ROOM VDDQ_KLM_PWR_VR
J 0
(1500 700);
DISPLAY 1.361702 (1500 700);
PAINT ORANGE (1500 700);
DISPLAY INVISIBLE (1500 700);
FORCEPROP 2 LAST SEC_TYPE 0402V
J 0
(1500 775);
DISPLAY 1.021277 (1500 775);
PAINT ORANGE (1500 775);
DISPLAY INVISIBLE (1500 775);
FORCEPROP 2 LAST SEC 1
J 0
(1500 775);
DISPLAY 0.680851 (1500 775);
PAINT MONO (1500 775);
DISPLAY INVISIBLE (1500 775);
FORCEADD CAP_A..1
(600 -100);
FORCEPROP 1 LAST PART_NUMBER A36096-030
J 0
(650 -250);
DISPLAY 0.617021 (650 -250);
PAINT BLUE (650 -250);
FORCEPROP 1 LASTPIN (600 0) $PN 1
J 0
(610 -20);
DISPLAY 0.617021 (610 -20);
PAINT ORANGE (610 -20);
FORCEPROP 1 LAST MATERIAL X7R
J 0
(650 -200);
DISPLAY 0.617021 (650 -200);
PAINT SKYBLUE (650 -200);
FORCEPROP 1 LAST PACK_TYPE 0402V
J 0
(650 -300);
DISPLAY 0.617021 (650 -300);
PAINT SKYBLUE (650 -300);
FORCEPROP 1 LASTPIN (600 -200) $PN 2
J 0
(610 -220);
DISPLAY 0.617021 (610 -220);
PAINT ORANGE (610 -220);
FORCEPROP 1 LAST VOLTAGE 16V
J 0
(650 -100);
DISPLAY 0.617021 (650 -100);
PAINT SKYBLUE (650 -100);
FORCEPROP 1 LAST TOLERANCE 10%
J 0
(650 -150);
DISPLAY 0.617021 (650 -150);
PAINT SKYBLUE (650 -150);
FORCEPROP 1 LAST VALUE 0.1UF
J 0
(650 -50);
DISPLAY 0.617021 (650 -50);
PAINT SKYBLUE (650 -50);
FORCEPROP 1 LAST LOCATION C25W13
J 0
(650 0);
DISPLAY 0.617021 (650 0);
PAINT AQUA (650 0);
FORCEPROP 2 LAST CDS_LOCATION C25W13
J 0
(650 0);
DISPLAY 0.617021 (650 0);
PAINT AQUA (650 0);
DISPLAY INVISIBLE (650 0);
FORCEPROP 2 LAST SEC 1
J 0
(650 125);
DISPLAY 0.680851 (650 125);
PAINT MONO (650 125);
DISPLAY INVISIBLE (650 125);
FORCEPROP 2 LAST SEC_TYPE 0402V
J 0
(650 125);
DISPLAY 1.021277 (650 125);
PAINT ORANGE (650 125);
DISPLAY INVISIBLE (650 125);
FORCEPROP 2 LAST ROOM VDDQ_KLM_PWR_VR
J 0
(650 50);
DISPLAY 1.361702 (650 50);
PAINT ORANGE (650 50);
DISPLAY INVISIBLE (650 50);
FORCEPROP 2 LAST CDS_SEC 1
J 0
(650 50);
PAINT ORANGE (650 50);
DISPLAY INVISIBLE (650 50);
FORCEPROP 2 LAST CDS_LIB dev_discrete
J 0
(600 -100);
PAINT ORANGE (600 -100);
DISPLAY INVISIBLE (600 -100);
FORCEPROP 1 LAST PATH I217
J 0
(650 50);
DISPLAY 0.978723 (650 50);
PAINT WHITE (650 50);
DISPLAY INVISIBLE (650 50);
FORCEADD CAP..1
R 2
(1950 -1900);
FORCEPROP 1 LAST PART_NUMBER A36096-155
J 0
(2000 -2025);
DISPLAY 0.617021 (2000 -2025);
PAINT BLUE (2000 -2025);
FORCEPROP 1 LAST MATERIAL X7R
J 0
(2000 -1975);
DISPLAY 0.617021 (2000 -1975);
PAINT SKYBLUE (2000 -1975);
FORCEPROP 1 LAST TOLERANCE 10%
J 0
(2000 -1925);
DISPLAY 0.617021 (2000 -1925);
PAINT SKYBLUE (2000 -1925);
FORCEPROP 1 LAST PACK_TYPE 0402
J 0
(2000 -2075);
DISPLAY 0.617021 (2000 -2075);
PAINT SKYBLUE (2000 -2075);
FORCEPROP 1 LAST LOCATION C1W20
J 0
(2000 -1775);
DISPLAY 0.617021 (2000 -1775);
PAINT AQUA (2000 -1775);
FORCEPROP 1 LAST VALUE 0.22UF
J 0
(2000 -1825);
DISPLAY 0.617021 (2000 -1825);
PAINT SKYBLUE (2000 -1825);
FORCEPROP 1 LASTPIN (1950 -1800) $PN 1
J 2
(1940 -1820);
DISPLAY 0.617021 (1940 -1820);
PAINT ORANGE (1940 -1820);
FORCEPROP 1 LAST VOLTAGE 16V
J 0
(2000 -1875);
DISPLAY 0.617021 (2000 -1875);
PAINT SKYBLUE (2000 -1875);
FORCEPROP 1 LASTPIN (1950 -2000) $PN 2
J 2
(1940 -2020);
DISPLAY 0.617021 (1940 -2020);
PAINT ORANGE (1940 -2020);
FORCEPROP 2 LAST CDS_LOCATION C1W20
J 2
(1900 -1800);
DISPLAY 0.617021 (1900 -1800);
PAINT AQUA (1900 -1800);
DISPLAY INVISIBLE (1900 -1800);
FORCEPROP 2 LAST CDS_LIB mstr_discrete
J 0
(1950 -1900);
PAINT ORANGE (1950 -1900);
DISPLAY INVISIBLE (1950 -1900);
FORCEPROP 2 LAST SEC_TYPE 0402
J 0
(1900 -1700);
DISPLAY 1.021277 (1900 -1700);
PAINT ORANGE (1900 -1700);
DISPLAY INVISIBLE (1900 -1700);
FORCEPROP 2 LAST SEC 1
J 0
(1900 -1700);
DISPLAY 0.680851 (1900 -1700);
PAINT MONO (1900 -1700);
DISPLAY INVISIBLE (1900 -1700);
FORCEPROP 1 LAST PATH I220
J 0
(1900 -1750);
DISPLAY 0.978723 (1900 -1750);
PAINT WHITE (1900 -1750);
DISPLAY INVISIBLE (1900 -1750);
FORCEPROP 2 LAST ROOM OCP_STEERING
J 0
(1950 -1900);
PAINT MONO (1950 -1900);
DISPLAY INVISIBLE (1950 -1900);
FORCEADD GND..1
(1950 -2100);
FORCEPROP 3 LASTPIN (1950 -2050) SIG_NAME GND\g
J 0
(1960 -2040);
DISPLAY 0.659574 (1960 -2040);
PAINT MONO (1960 -2040);
DISPLAY INVISIBLE (1960 -2040);
FORCEPROP 1 LAST HDL_POWER GND
J 0
(1950 -1950);
DISPLAY 0.872340 (1950 -1950);
PAINT GREEN (1950 -1950);
DISPLAY INVISIBLE (1950 -1950);
FORCEPROP 1 LAST BODY_TYPE PLUMBING
J 0
(1905 -2143);
DISPLAY 0.340426 (1905 -2143);
PAINT GREEN (1905 -2143);
DISPLAY INVISIBLE (1905 -2143);
FORCEPROP 1 LAST PATH I221
J 0
(2025 -2100);
DISPLAY 0.872340 (2025 -2100);
PAINT AQUA (2025 -2100);
DISPLAY INVISIBLE (2025 -2100);
FORCEPROP 2 LAST CDS_LIB mstr_symbols
J 0
(1950 -2100);
PAINT MONO (1950 -2100);
DISPLAY INVISIBLE (1950 -2100);
FORCEPROP 1 LAST SIZE 1B
J 0
(2025 -2150);
DISPLAY 0.872340 (2025 -2150);
PAINT AQUA (2025 -2150);
DISPLAY INVISIBLE (2025 -2150);
FORCEPROP 1 LAST VOLTAGE 0.0V
J 0
(1905 -2143);
DISPLAY 0.340426 (1905 -2143);
PAINT GREEN (1905 -2143);
DISPLAY INVISIBLE (1905 -2143);
FORCEADD RES..2
R 1
(-975 1525);
FORCEPROP 1 LAST PACK_TYPE 0402
J 0
(-50 1540);
DISPLAY 0.617021 (-50 1540);
PAINT SKYBLUE (-50 1540);
FORCEPROP 1 LAST WATTAGE 1/16W
J 0
(-225 1540);
DISPLAY 0.617021 (-225 1540);
PAINT SKYBLUE (-225 1540);
FORCEPROP 1 LAST TOLERANCE 1%
J 0
(-325 1545);
DISPLAY 0.617021 (-325 1545);
PAINT SKYBLUE (-325 1545);
FORCEPROP 1 LASTPIN (-1075 1525) $PN 1
J 0
(-1087 1530);
DISPLAY 0.617021 (-1087 1530);
PAINT ORANGE (-1087 1530);
FORCEPROP 1 LASTPIN (-875 1525) $PN 2
J 0
(-885 1530);
DISPLAY 0.617021 (-885 1530);
PAINT ORANGE (-885 1530);
FORCEPROP 1 LAST VALUE 2.7K
J 0
(-475 1545);
DISPLAY 0.617021 (-475 1545);
PAINT SKYBLUE (-475 1545);
FORCEPROP 1 LAST MATERIAL CHIP
J 0
(-725 1515);
DISPLAY 0.617021 (-725 1515);
PAINT SKYBLUE (-725 1515);
FORCEPROP 1 LAST LOCATION R25W30
J 0
(-1275 1520);
DISPLAY 0.617021 (-1275 1520);
PAINT AQUA (-1275 1520);
FORCEPROP 1 LAST PART_NUMBER G21796-344
J 0
(-725 1540);
DISPLAY 0.617021 (-725 1540);
PAINT BLUE (-725 1540);
FORCEPROP 1 LAST PATH I222
R 1
J 0
(-1150 1575);
DISPLAY 0.978723 (-1150 1575);
PAINT WHITE (-1150 1575);
DISPLAY INVISIBLE (-1150 1575);
FORCEPROP 2 LAST CDS_LIB mstr_discrete
R 1
J 0
(-975 1525);
PAINT ORANGE (-975 1525);
DISPLAY INVISIBLE (-975 1525);
FORCEPROP 2 LAST SEC_TYPE 0402
R 1
J 0
(-1200 1575);
DISPLAY 1.021277 (-1200 1575);
PAINT ORANGE (-1200 1575);
DISPLAY INVISIBLE (-1200 1575);
FORCEPROP 2 LAST SEC 1
R 1
J 0
(-1200 1575);
DISPLAY 0.680851 (-1200 1575);
PAINT MONO (-1200 1575);
DISPLAY INVISIBLE (-1200 1575);
FORCEADD 120R2F-GP..1
R 1
(-950 1675);
FORCEPROP 2 LAST PACK_SIZE 0402
J 0
(-50 1675);
DISPLAY 0.638298 (-50 1675);
PAINT GREEN (-50 1675);
FORCEPROP 2 LAST RATED 1/16W
J 0
(-225 1675);
DISPLAY 0.638298 (-225 1675);
PAINT GREEN (-225 1675);
FORCEPROP 2 LAST ATTRIBUTE 120OHM
J 0
(-500 1675);
DISPLAY 0.638298 (-500 1675);
PAINT GREEN (-500 1675);
FORCEPROP 1 LAST LOCATION R25W27
J 0
(-1275 1675);
DISPLAY 0.617021 (-1275 1675);
PAINT GREEN (-1275 1675);
FORCEPROP 2 LASTPIN (-1075 1675) $PN 1
J 2
(-1060 1685);
DISPLAY 0.808511 (-1060 1685);
PAINT ORANGE (-1060 1685);
FORCEPROP 2 LAST TOLERANCE 1%
J 0
(-325 1675);
DISPLAY 0.638298 (-325 1675);
PAINT GREEN (-325 1675);
FORCEPROP 2 LASTPIN (-825 1675) $PN 2
J 0
(-815 1685);
DISPLAY 0.808511 (-815 1685);
PAINT ORANGE (-815 1685);
FORCEPROP 1 LAST VALUE 120R2F-GP
J 0
(-725 1675);
DISPLAY 0.617021 (-725 1675);
PAINT GREEN (-725 1675);
FORCEPROP 1 LAST PACK_TYPE RCL_GP
R 1
J 0
(-950 1675);
DISPLAY 0.617021 (-950 1675);
PAINT GREEN (-950 1675);
DISPLAY INVISIBLE (-950 1675);
FORCEPROP 2 LAST SEC 1
J 0
(-725 1725);
DISPLAY 0.680851 (-725 1725);
PAINT MONO (-725 1725);
DISPLAY INVISIBLE (-725 1725);
FORCEPROP 2 LAST SEC_TYPE RCL_GP
J 0
(-725 1725);
DISPLAY 1.021277 (-725 1725);
PAINT ORANGE (-725 1725);
DISPLAY INVISIBLE (-725 1725);
FORCEPROP 1 LAST PART_NUMBER 64.12005.6DL
R 1
J 0
(-950 1675);
DISPLAY 0.617021 (-950 1675);
PAINT GREEN (-950 1675);
DISPLAY INVISIBLE (-950 1675);
FORCEPROP 2 LAST CDS_LIB w_hdl
R 1
J 0
(-950 1675);
DISPLAY INVISIBLE (-950 1675);
FORCEPROP 1 LAST CDS_LMAN_SYM_OUTLINE -50,75,50,-75
R 1
J 0
(-950 1675);
DISPLAY 0.468085 (-950 1675);
PAINT GREEN (-950 1675);
DISPLAY INVISIBLE (-950 1675);
FORCEPROP 1 LAST PATH I223
R 1
J 0
(-950 1675);
DISPLAY 0.617021 (-950 1675);
PAINT GREEN (-950 1675);
DISPLAY INVISIBLE (-950 1675);
FORCEADD 120R2F-GP..1
R 1
(-950 1625);
FORCEPROP 2 LAST RATED 1/16W
J 0
(-225 1625);
DISPLAY 0.638298 (-225 1625);
PAINT GREEN (-225 1625);
FORCEPROP 2 LAST ATTRIBUTE 120OHM
J 0
(-500 1625);
DISPLAY 0.638298 (-500 1625);
PAINT GREEN (-500 1625);
FORCEPROP 2 LASTPIN (-1075 1625) $PN 1
J 2
(-1060 1635);
DISPLAY 0.808511 (-1060 1635);
PAINT ORANGE (-1060 1635);
FORCEPROP 1 LAST LOCATION R25W28
J 0
(-1275 1625);
DISPLAY 0.617021 (-1275 1625);
PAINT GREEN (-1275 1625);
FORCEPROP 1 LAST VALUE 120R2F-GP
J 0
(-725 1625);
DISPLAY 0.617021 (-725 1625);
PAINT GREEN (-725 1625);
FORCEPROP 2 LASTPIN (-825 1625) $PN 2
J 0
(-815 1635);
DISPLAY 0.808511 (-815 1635);
PAINT ORANGE (-815 1635);
FORCEPROP 2 LAST TOLERANCE 1%
J 0
(-325 1625);
DISPLAY 0.638298 (-325 1625);
PAINT GREEN (-325 1625);
FORCEPROP 2 LAST PACK_SIZE 0402
J 0
(-50 1625);
DISPLAY 0.638298 (-50 1625);
PAINT GREEN (-50 1625);
FORCEPROP 1 LAST CDS_LMAN_SYM_OUTLINE -50,75,50,-75
R 1
J 0
(-950 1625);
DISPLAY 0.468085 (-950 1625);
PAINT GREEN (-950 1625);
DISPLAY INVISIBLE (-950 1625);
FORCEPROP 2 LAST CDS_LIB w_hdl
R 1
J 0
(-950 1625);
DISPLAY INVISIBLE (-950 1625);
FORCEPROP 1 LAST PART_NUMBER 64.12005.6DL
R 1
J 0
(-950 1625);
DISPLAY 0.617021 (-950 1625);
PAINT GREEN (-950 1625);
DISPLAY INVISIBLE (-950 1625);
FORCEPROP 2 LAST SEC_TYPE RCL_GP
J 0
(-725 1675);
DISPLAY 1.021277 (-725 1675);
PAINT ORANGE (-725 1675);
DISPLAY INVISIBLE (-725 1675);
FORCEPROP 2 LAST SEC 1
J 0
(-725 1675);
DISPLAY 0.680851 (-725 1675);
PAINT MONO (-725 1675);
DISPLAY INVISIBLE (-725 1675);
FORCEPROP 1 LAST PACK_TYPE RCL_GP
R 1
J 0
(-950 1625);
DISPLAY 0.617021 (-950 1625);
PAINT GREEN (-950 1625);
DISPLAY INVISIBLE (-950 1625);
FORCEPROP 1 LAST PATH I224
R 1
J 0
(-950 1625);
DISPLAY 0.617021 (-950 1625);
PAINT GREEN (-950 1625);
DISPLAY INVISIBLE (-950 1625);
FORCEADD 120R2F-GP..1
R 1
(-950 1575);
FORCEPROP 2 LAST PACK_SIZE 0402
J 0
(-50 1575);
DISPLAY 0.638298 (-50 1575);
PAINT GREEN (-50 1575);
FORCEPROP 0 LAST POP NOPOP
J 0
(-1050 1550);
DISPLAY 1.021277 (-1050 1550);
PAINT RED (-1050 1550);
FORCEPROP 1 LAST LOCATION R25W29
J 0
(-1275 1575);
DISPLAY 0.617021 (-1275 1575);
PAINT GREEN (-1275 1575);
FORCEPROP 2 LASTPIN (-825 1575) $PN 2
J 0
(-815 1585);
DISPLAY 0.808511 (-815 1585);
PAINT ORANGE (-815 1585);
FORCEPROP 2 LASTPIN (-1075 1575) $PN 1
J 2
(-1060 1585);
DISPLAY 0.808511 (-1060 1585);
PAINT ORANGE (-1060 1585);
FORCEPROP 2 LAST RATED 1/16W
J 0
(-225 1575);
DISPLAY 0.638298 (-225 1575);
PAINT GREEN (-225 1575);
FORCEPROP 2 LAST TOLERANCE 1%
J 0
(-325 1575);
DISPLAY 0.638298 (-325 1575);
PAINT GREEN (-325 1575);
FORCEPROP 2 LAST ATTRIBUTE 120OHM
J 0
(-500 1575);
DISPLAY 0.638298 (-500 1575);
PAINT GREEN (-500 1575);
FORCEPROP 1 LAST VALUE 120R2F-GP
J 0
(-725 1575);
DISPLAY 0.617021 (-725 1575);
PAINT GREEN (-725 1575);
FORCEPROP 1 LAST CDS_LMAN_SYM_OUTLINE -50,75,50,-75
R 1
J 0
(-950 1575);
DISPLAY 0.468085 (-950 1575);
PAINT GREEN (-950 1575);
DISPLAY INVISIBLE (-950 1575);
FORCEPROP 2 LAST CDS_LIB w_hdl
R 1
J 0
(-950 1575);
DISPLAY INVISIBLE (-950 1575);
FORCEPROP 1 LAST PART_NUMBER 64.12005.6DL
R 1
J 0
(-950 1575);
DISPLAY 0.617021 (-950 1575);
PAINT GREEN (-950 1575);
DISPLAY INVISIBLE (-950 1575);
FORCEPROP 2 LAST SEC_TYPE RCL_GP
J 0
(-725 1625);
DISPLAY 1.021277 (-725 1625);
PAINT ORANGE (-725 1625);
DISPLAY INVISIBLE (-725 1625);
FORCEPROP 2 LAST SEC 1
J 0
(-725 1625);
DISPLAY 0.680851 (-725 1625);
PAINT MONO (-725 1625);
DISPLAY INVISIBLE (-725 1625);
FORCEPROP 1 LAST PACK_TYPE RCL_GP
R 1
J 0
(-950 1575);
DISPLAY 0.617021 (-950 1575);
PAINT GREEN (-950 1575);
DISPLAY INVISIBLE (-950 1575);
FORCEPROP 1 LAST PATH I225
R 1
J 0
(-950 1575);
DISPLAY 0.617021 (-950 1575);
PAINT GREEN (-950 1575);
DISPLAY INVISIBLE (-950 1575);
FORCEADD 120R2F-GP..1
R 1
(-950 1475);
FORCEPROP 2 LAST PACK_SIZE 0402
J 0
(-50 1475);
DISPLAY 0.638298 (-50 1475);
PAINT GREEN (-50 1475);
FORCEPROP 2 LAST ATTRIBUTE 120OHM
J 0
(-500 1475);
DISPLAY 0.638298 (-500 1475);
PAINT GREEN (-500 1475);
FORCEPROP 1 LAST LOCATION R25W31
J 0
(-1275 1475);
DISPLAY 0.617021 (-1275 1475);
PAINT GREEN (-1275 1475);
FORCEPROP 1 LAST VALUE 120R2F-GP
J 0
(-725 1475);
DISPLAY 0.617021 (-725 1475);
PAINT GREEN (-725 1475);
FORCEPROP 2 LASTPIN (-1075 1475) $PN 1
J 2
(-1060 1485);
DISPLAY 0.808511 (-1060 1485);
PAINT ORANGE (-1060 1485);
FORCEPROP 2 LAST RATED 1/16W
J 0
(-225 1475);
DISPLAY 0.638298 (-225 1475);
PAINT GREEN (-225 1475);
FORCEPROP 2 LAST TOLERANCE 1%
J 0
(-325 1475);
DISPLAY 0.638298 (-325 1475);
PAINT GREEN (-325 1475);
FORCEPROP 2 LASTPIN (-825 1475) $PN 2
J 0
(-815 1485);
DISPLAY 0.808511 (-815 1485);
PAINT ORANGE (-815 1485);
FORCEPROP 1 LAST PATH I226
R 1
J 0
(-950 1475);
DISPLAY 0.617021 (-950 1475);
PAINT GREEN (-950 1475);
DISPLAY INVISIBLE (-950 1475);
FORCEPROP 1 LAST PACK_TYPE RCL_GP
R 1
J 0
(-950 1475);
DISPLAY 0.617021 (-950 1475);
PAINT GREEN (-950 1475);
DISPLAY INVISIBLE (-950 1475);
FORCEPROP 2 LAST SEC 1
J 0
(-725 1525);
DISPLAY 0.680851 (-725 1525);
PAINT MONO (-725 1525);
DISPLAY INVISIBLE (-725 1525);
FORCEPROP 2 LAST SEC_TYPE RCL_GP
J 0
(-725 1525);
DISPLAY 1.021277 (-725 1525);
PAINT ORANGE (-725 1525);
DISPLAY INVISIBLE (-725 1525);
FORCEPROP 1 LAST PART_NUMBER 64.12005.6DL
R 1
J 0
(-950 1475);
DISPLAY 0.617021 (-950 1475);
PAINT GREEN (-950 1475);
DISPLAY INVISIBLE (-950 1475);
FORCEPROP 2 LAST CDS_LIB w_hdl
R 1
J 0
(-950 1475);
DISPLAY INVISIBLE (-950 1475);
FORCEPROP 1 LAST CDS_LMAN_SYM_OUTLINE -50,75,50,-75
R 1
J 0
(-950 1475);
DISPLAY 0.468085 (-950 1475);
PAINT GREEN (-950 1475);
DISPLAY INVISIBLE (-950 1475);
FORCEADD 120R2F-GP..1
R 1
(-950 1425);
FORCEPROP 2 LAST PACK_SIZE 0402
J 0
(-50 1425);
DISPLAY 0.638298 (-50 1425);
PAINT GREEN (-50 1425);
FORCEPROP 2 LAST ATTRIBUTE 120OHM
J 0
(-500 1425);
DISPLAY 0.638298 (-500 1425);
PAINT GREEN (-500 1425);
FORCEPROP 1 LAST LOCATION R25W32
J 0
(-1275 1425);
DISPLAY 0.617021 (-1275 1425);
PAINT GREEN (-1275 1425);
FORCEPROP 1 LAST VALUE 120R2F-GP
J 0
(-725 1425);
DISPLAY 0.617021 (-725 1425);
PAINT GREEN (-725 1425);
FORCEPROP 2 LASTPIN (-825 1425) $PN 2
J 0
(-815 1435);
DISPLAY 0.808511 (-815 1435);
PAINT ORANGE (-815 1435);
FORCEPROP 2 LASTPIN (-1075 1425) $PN 1
J 2
(-1060 1435);
DISPLAY 0.808511 (-1060 1435);
PAINT ORANGE (-1060 1435);
FORCEPROP 2 LAST RATED 1/16W
J 0
(-225 1425);
DISPLAY 0.638298 (-225 1425);
PAINT GREEN (-225 1425);
FORCEPROP 2 LAST TOLERANCE 1%
J 0
(-325 1425);
DISPLAY 0.638298 (-325 1425);
PAINT GREEN (-325 1425);
FORCEPROP 1 LAST PATH I227
R 1
J 0
(-950 1425);
DISPLAY 0.617021 (-950 1425);
PAINT GREEN (-950 1425);
DISPLAY INVISIBLE (-950 1425);
FORCEPROP 1 LAST PACK_TYPE RCL_GP
R 1
J 0
(-950 1425);
DISPLAY 0.617021 (-950 1425);
PAINT GREEN (-950 1425);
DISPLAY INVISIBLE (-950 1425);
FORCEPROP 2 LAST SEC 1
J 0
(-725 1475);
DISPLAY 0.680851 (-725 1475);
PAINT MONO (-725 1475);
DISPLAY INVISIBLE (-725 1475);
FORCEPROP 2 LAST SEC_TYPE RCL_GP
J 0
(-725 1475);
DISPLAY 1.021277 (-725 1475);
PAINT ORANGE (-725 1475);
DISPLAY INVISIBLE (-725 1475);
FORCEPROP 1 LAST PART_NUMBER 64.12005.6DL
R 1
J 0
(-950 1425);
DISPLAY 0.617021 (-950 1425);
PAINT GREEN (-950 1425);
DISPLAY INVISIBLE (-950 1425);
FORCEPROP 2 LAST CDS_LIB w_hdl
R 1
J 0
(-950 1425);
DISPLAY INVISIBLE (-950 1425);
FORCEPROP 1 LAST CDS_LMAN_SYM_OUTLINE -50,75,50,-75
R 1
J 0
(-950 1425);
DISPLAY 0.468085 (-950 1425);
PAINT GREEN (-950 1425);
DISPLAY INVISIBLE (-950 1425);
FORCEADD 120R2F-GP..1
R 1
(-950 1375);
FORCEPROP 1 LAST LOCATION R25W33
J 0
(-1275 1375);
DISPLAY 0.617021 (-1275 1375);
PAINT GREEN (-1275 1375);
FORCEPROP 2 LAST PACK_SIZE 0402
J 0
(-50 1375);
DISPLAY 0.638298 (-50 1375);
PAINT GREEN (-50 1375);
FORCEPROP 2 LAST ATTRIBUTE 120OHM
J 0
(-500 1375);
DISPLAY 0.638298 (-500 1375);
PAINT GREEN (-500 1375);
FORCEPROP 2 LASTPIN (-825 1375) $PN 2
J 0
(-815 1385);
DISPLAY 0.808511 (-815 1385);
PAINT ORANGE (-815 1385);
FORCEPROP 2 LASTPIN (-1075 1375) $PN 1
J 2
(-1060 1385);
DISPLAY 0.808511 (-1060 1385);
PAINT ORANGE (-1060 1385);
FORCEPROP 2 LAST RATED 1/16W
J 0
(-225 1375);
DISPLAY 0.638298 (-225 1375);
PAINT GREEN (-225 1375);
FORCEPROP 2 LAST TOLERANCE 1%
J 0
(-325 1375);
DISPLAY 0.638298 (-325 1375);
PAINT GREEN (-325 1375);
FORCEPROP 1 LAST VALUE 120R2F-GP
J 0
(-725 1375);
DISPLAY 0.617021 (-725 1375);
PAINT GREEN (-725 1375);
FORCEPROP 1 LAST PATH I228
R 1
J 0
(-950 1375);
DISPLAY 0.617021 (-950 1375);
PAINT GREEN (-950 1375);
DISPLAY INVISIBLE (-950 1375);
FORCEPROP 1 LAST PACK_TYPE RCL_GP
R 1
J 0
(-950 1375);
DISPLAY 0.617021 (-950 1375);
PAINT GREEN (-950 1375);
DISPLAY INVISIBLE (-950 1375);
FORCEPROP 2 LAST SEC 1
J 0
(-725 1425);
DISPLAY 0.680851 (-725 1425);
PAINT MONO (-725 1425);
DISPLAY INVISIBLE (-725 1425);
FORCEPROP 2 LAST SEC_TYPE RCL_GP
J 0
(-725 1425);
DISPLAY 1.021277 (-725 1425);
PAINT ORANGE (-725 1425);
DISPLAY INVISIBLE (-725 1425);
FORCEPROP 1 LAST PART_NUMBER 64.12005.6DL
R 1
J 0
(-950 1375);
DISPLAY 0.617021 (-950 1375);
PAINT GREEN (-950 1375);
DISPLAY INVISIBLE (-950 1375);
FORCEPROP 2 LAST CDS_LIB w_hdl
R 1
J 0
(-950 1375);
DISPLAY INVISIBLE (-950 1375);
FORCEPROP 1 LAST CDS_LMAN_SYM_OUTLINE -50,75,50,-75
R 1
J 0
(-950 1375);
DISPLAY 0.468085 (-950 1375);
PAINT GREEN (-950 1375);
DISPLAY INVISIBLE (-950 1375);
FORCEADD 120R2F-GP..1
R 1
(-950 1325);
FORCEPROP 2 LAST PACK_SIZE 0402
J 0
(-50 1325);
DISPLAY 0.638298 (-50 1325);
PAINT GREEN (-50 1325);
FORCEPROP 2 LAST ATTRIBUTE 120OHM
J 0
(-500 1325);
DISPLAY 0.638298 (-500 1325);
PAINT GREEN (-500 1325);
FORCEPROP 1 LAST VALUE 120R2F-GP
J 0
(-725 1325);
DISPLAY 0.617021 (-725 1325);
PAINT GREEN (-725 1325);
FORCEPROP 2 LASTPIN (-825 1325) $PN 2
J 0
(-815 1335);
DISPLAY 0.808511 (-815 1335);
PAINT ORANGE (-815 1335);
FORCEPROP 2 LASTPIN (-1075 1325) $PN 1
J 2
(-1060 1335);
DISPLAY 0.808511 (-1060 1335);
PAINT ORANGE (-1060 1335);
FORCEPROP 2 LAST RATED 1/16W
J 0
(-225 1325);
DISPLAY 0.638298 (-225 1325);
PAINT GREEN (-225 1325);
FORCEPROP 2 LAST TOLERANCE 1%
J 0
(-325 1325);
DISPLAY 0.638298 (-325 1325);
PAINT GREEN (-325 1325);
FORCEPROP 1 LAST LOCATION R25W34
J 0
(-1275 1325);
DISPLAY 0.617021 (-1275 1325);
PAINT GREEN (-1275 1325);
FORCEPROP 1 LAST PATH I229
R 1
J 0
(-950 1325);
DISPLAY 0.617021 (-950 1325);
PAINT GREEN (-950 1325);
DISPLAY INVISIBLE (-950 1325);
FORCEPROP 1 LAST PACK_TYPE RCL_GP
R 1
J 0
(-950 1325);
DISPLAY 0.617021 (-950 1325);
PAINT GREEN (-950 1325);
DISPLAY INVISIBLE (-950 1325);
FORCEPROP 2 LAST SEC 1
J 0
(-725 1375);
DISPLAY 0.680851 (-725 1375);
PAINT MONO (-725 1375);
DISPLAY INVISIBLE (-725 1375);
FORCEPROP 2 LAST SEC_TYPE RCL_GP
J 0
(-725 1375);
DISPLAY 1.021277 (-725 1375);
PAINT ORANGE (-725 1375);
DISPLAY INVISIBLE (-725 1375);
FORCEPROP 1 LAST PART_NUMBER 64.12005.6DL
R 1
J 0
(-950 1325);
DISPLAY 0.617021 (-950 1325);
PAINT GREEN (-950 1325);
DISPLAY INVISIBLE (-950 1325);
FORCEPROP 2 LAST CDS_LIB w_hdl
R 1
J 0
(-950 1325);
DISPLAY INVISIBLE (-950 1325);
FORCEPROP 1 LAST CDS_LMAN_SYM_OUTLINE -50,75,50,-75
R 1
J 0
(-950 1325);
DISPLAY 0.468085 (-950 1325);
PAINT GREEN (-950 1325);
DISPLAY INVISIBLE (-950 1325);
FORCEADD 120R2F-GP..1
R 1
(-950 1275);
FORCEPROP 2 LAST PACK_SIZE 0402
J 0
(-50 1275);
DISPLAY 0.638298 (-50 1275);
PAINT GREEN (-50 1275);
FORCEPROP 2 LAST ATTRIBUTE 120OHM
J 0
(-500 1275);
DISPLAY 0.638298 (-500 1275);
PAINT GREEN (-500 1275);
FORCEPROP 2 LASTPIN (-825 1275) $PN 2
J 0
(-815 1285);
DISPLAY 0.808511 (-815 1285);
PAINT ORANGE (-815 1285);
FORCEPROP 1 LAST VALUE 120R2F-GP
J 0
(-725 1275);
DISPLAY 0.617021 (-725 1275);
PAINT GREEN (-725 1275);
FORCEPROP 2 LAST RATED 1/16W
J 0
(-225 1275);
DISPLAY 0.638298 (-225 1275);
PAINT GREEN (-225 1275);
FORCEPROP 2 LAST TOLERANCE 1%
J 0
(-325 1275);
DISPLAY 0.638298 (-325 1275);
PAINT GREEN (-325 1275);
FORCEPROP 2 LASTPIN (-1075 1275) $PN 1
J 2
(-1060 1285);
DISPLAY 0.808511 (-1060 1285);
PAINT ORANGE (-1060 1285);
FORCEPROP 1 LAST LOCATION R25W35
J 0
(-1275 1275);
DISPLAY 0.617021 (-1275 1275);
PAINT GREEN (-1275 1275);
FORCEPROP 1 LAST PATH I230
R 1
J 0
(-950 1275);
DISPLAY 0.617021 (-950 1275);
PAINT GREEN (-950 1275);
DISPLAY INVISIBLE (-950 1275);
FORCEPROP 1 LAST PACK_TYPE RCL_GP
R 1
J 0
(-950 1275);
DISPLAY 0.617021 (-950 1275);
PAINT GREEN (-950 1275);
DISPLAY INVISIBLE (-950 1275);
FORCEPROP 2 LAST SEC 1
J 0
(-725 1325);
DISPLAY 0.680851 (-725 1325);
PAINT MONO (-725 1325);
DISPLAY INVISIBLE (-725 1325);
FORCEPROP 2 LAST SEC_TYPE RCL_GP
J 0
(-725 1325);
DISPLAY 1.021277 (-725 1325);
PAINT ORANGE (-725 1325);
DISPLAY INVISIBLE (-725 1325);
FORCEPROP 1 LAST PART_NUMBER 64.12005.6DL
R 1
J 0
(-950 1275);
DISPLAY 0.617021 (-950 1275);
PAINT GREEN (-950 1275);
DISPLAY INVISIBLE (-950 1275);
FORCEPROP 2 LAST CDS_LIB w_hdl
R 1
J 0
(-950 1275);
DISPLAY INVISIBLE (-950 1275);
FORCEPROP 1 LAST CDS_LMAN_SYM_OUTLINE -50,75,50,-75
R 1
J 0
(-950 1275);
DISPLAY 0.468085 (-950 1275);
PAINT GREEN (-950 1275);
DISPLAY INVISIBLE (-950 1275);
FORCEADD 120R2F-GP..1
R 1
(-950 1225);
FORCEPROP 2 LAST PACK_SIZE 0402
J 0
(-50 1225);
DISPLAY 0.638298 (-50 1225);
PAINT GREEN (-50 1225);
FORCEPROP 2 LAST ATTRIBUTE 120OHM
J 0
(-500 1225);
DISPLAY 0.638298 (-500 1225);
PAINT GREEN (-500 1225);
FORCEPROP 1 LAST VALUE 120R2F-GP
J 0
(-725 1225);
DISPLAY 0.617021 (-725 1225);
PAINT GREEN (-725 1225);
FORCEPROP 2 LAST TOLERANCE 1%
J 0
(-325 1225);
DISPLAY 0.638298 (-325 1225);
PAINT GREEN (-325 1225);
FORCEPROP 2 LASTPIN (-825 1225) $PN 2
J 0
(-815 1235);
DISPLAY 0.808511 (-815 1235);
PAINT ORANGE (-815 1235);
FORCEPROP 1 LAST LOCATION R25W36
J 0
(-1275 1225);
DISPLAY 0.617021 (-1275 1225);
PAINT GREEN (-1275 1225);
FORCEPROP 2 LASTPIN (-1075 1225) $PN 1
J 2
(-1060 1235);
DISPLAY 0.808511 (-1060 1235);
PAINT ORANGE (-1060 1235);
FORCEPROP 2 LAST RATED 1/16W
J 0
(-225 1225);
DISPLAY 0.638298 (-225 1225);
PAINT GREEN (-225 1225);
FORCEPROP 1 LAST PATH I231
R 1
J 0
(-950 1225);
DISPLAY 0.617021 (-950 1225);
PAINT GREEN (-950 1225);
DISPLAY INVISIBLE (-950 1225);
FORCEPROP 1 LAST PACK_TYPE RCL_GP
R 1
J 0
(-950 1225);
DISPLAY 0.617021 (-950 1225);
PAINT GREEN (-950 1225);
DISPLAY INVISIBLE (-950 1225);
FORCEPROP 2 LAST SEC 1
J 0
(-725 1275);
DISPLAY 0.680851 (-725 1275);
PAINT MONO (-725 1275);
DISPLAY INVISIBLE (-725 1275);
FORCEPROP 2 LAST SEC_TYPE RCL_GP
J 0
(-725 1275);
DISPLAY 1.021277 (-725 1275);
PAINT ORANGE (-725 1275);
DISPLAY INVISIBLE (-725 1275);
FORCEPROP 1 LAST PART_NUMBER 64.12005.6DL
R 1
J 0
(-950 1225);
DISPLAY 0.617021 (-950 1225);
PAINT GREEN (-950 1225);
DISPLAY INVISIBLE (-950 1225);
FORCEPROP 2 LAST CDS_LIB w_hdl
R 1
J 0
(-950 1225);
DISPLAY INVISIBLE (-950 1225);
FORCEPROP 1 LAST CDS_LMAN_SYM_OUTLINE -50,75,50,-75
R 1
J 0
(-950 1225);
DISPLAY 0.468085 (-950 1225);
PAINT GREEN (-950 1225);
DISPLAY INVISIBLE (-950 1225);
FORCEADD 120R2F-GP..1
R 1
(-950 1175);
FORCEPROP 1 LAST LOCATION R25W37
J 0
(-1275 1175);
DISPLAY 0.617021 (-1275 1175);
PAINT GREEN (-1275 1175);
FORCEPROP 2 LAST ATTRIBUTE 120OHM
J 0
(-500 1175);
DISPLAY 0.638298 (-500 1175);
PAINT GREEN (-500 1175);
FORCEPROP 1 LAST VALUE 120R2F-GP
J 0
(-725 1175);
DISPLAY 0.617021 (-725 1175);
PAINT GREEN (-725 1175);
FORCEPROP 2 LASTPIN (-825 1175) $PN 2
J 0
(-815 1185);
DISPLAY 0.808511 (-815 1185);
PAINT ORANGE (-815 1185);
FORCEPROP 2 LASTPIN (-1075 1175) $PN 1
J 2
(-1060 1185);
DISPLAY 0.808511 (-1060 1185);
PAINT ORANGE (-1060 1185);
FORCEPROP 2 LAST RATED 1/16W
J 0
(-225 1175);
DISPLAY 0.638298 (-225 1175);
PAINT GREEN (-225 1175);
FORCEPROP 2 LAST TOLERANCE 1%
J 0
(-325 1175);
DISPLAY 0.638298 (-325 1175);
PAINT GREEN (-325 1175);
FORCEPROP 2 LAST PACK_SIZE 0402
J 0
(-50 1175);
DISPLAY 0.638298 (-50 1175);
PAINT GREEN (-50 1175);
FORCEPROP 1 LAST PATH I232
R 1
J 0
(-950 1175);
DISPLAY 0.617021 (-950 1175);
PAINT GREEN (-950 1175);
DISPLAY INVISIBLE (-950 1175);
FORCEPROP 1 LAST PACK_TYPE RCL_GP
R 1
J 0
(-950 1175);
DISPLAY 0.617021 (-950 1175);
PAINT GREEN (-950 1175);
DISPLAY INVISIBLE (-950 1175);
FORCEPROP 2 LAST SEC 1
J 0
(-725 1225);
DISPLAY 0.680851 (-725 1225);
PAINT MONO (-725 1225);
DISPLAY INVISIBLE (-725 1225);
FORCEPROP 2 LAST SEC_TYPE RCL_GP
J 0
(-725 1225);
DISPLAY 1.021277 (-725 1225);
PAINT ORANGE (-725 1225);
DISPLAY INVISIBLE (-725 1225);
FORCEPROP 1 LAST PART_NUMBER 64.12005.6DL
R 1
J 0
(-950 1175);
DISPLAY 0.617021 (-950 1175);
PAINT GREEN (-950 1175);
DISPLAY INVISIBLE (-950 1175);
FORCEPROP 2 LAST CDS_LIB w_hdl
R 1
J 0
(-950 1175);
DISPLAY INVISIBLE (-950 1175);
FORCEPROP 1 LAST CDS_LMAN_SYM_OUTLINE -50,75,50,-75
R 1
J 0
(-950 1175);
DISPLAY 0.468085 (-950 1175);
PAINT GREEN (-950 1175);
DISPLAY INVISIBLE (-950 1175);
FORCEADD 120R2F-GP..1
R 1
(-950 1125);
FORCEPROP 1 LAST LOCATION R25W38
J 0
(-1275 1125);
DISPLAY 0.617021 (-1275 1125);
PAINT GREEN (-1275 1125);
FORCEPROP 2 LAST ATTRIBUTE 120OHM
J 0
(-500 1125);
DISPLAY 0.638298 (-500 1125);
PAINT GREEN (-500 1125);
FORCEPROP 1 LAST VALUE 120R2F-GP
J 0
(-725 1125);
DISPLAY 0.617021 (-725 1125);
PAINT GREEN (-725 1125);
FORCEPROP 2 LASTPIN (-1075 1125) $PN 1
J 2
(-1060 1135);
DISPLAY 0.808511 (-1060 1135);
PAINT ORANGE (-1060 1135);
FORCEPROP 2 LAST RATED 1/16W
J 0
(-225 1125);
DISPLAY 0.638298 (-225 1125);
PAINT GREEN (-225 1125);
FORCEPROP 2 LAST TOLERANCE 1%
J 0
(-325 1125);
DISPLAY 0.638298 (-325 1125);
PAINT GREEN (-325 1125);
FORCEPROP 2 LASTPIN (-825 1125) $PN 2
J 0
(-815 1135);
DISPLAY 0.808511 (-815 1135);
PAINT ORANGE (-815 1135);
FORCEPROP 2 LAST PACK_SIZE 0402
J 0
(-50 1125);
DISPLAY 0.638298 (-50 1125);
PAINT GREEN (-50 1125);
FORCEPROP 1 LAST PATH I233
R 1
J 0
(-950 1125);
DISPLAY 0.617021 (-950 1125);
PAINT GREEN (-950 1125);
DISPLAY INVISIBLE (-950 1125);
FORCEPROP 1 LAST PACK_TYPE RCL_GP
R 1
J 0
(-950 1125);
DISPLAY 0.617021 (-950 1125);
PAINT GREEN (-950 1125);
DISPLAY INVISIBLE (-950 1125);
FORCEPROP 2 LAST SEC 1
J 0
(-725 1175);
DISPLAY 0.680851 (-725 1175);
PAINT MONO (-725 1175);
DISPLAY INVISIBLE (-725 1175);
FORCEPROP 2 LAST SEC_TYPE RCL_GP
J 0
(-725 1175);
DISPLAY 1.021277 (-725 1175);
PAINT ORANGE (-725 1175);
DISPLAY INVISIBLE (-725 1175);
FORCEPROP 1 LAST PART_NUMBER 64.12005.6DL
R 1
J 0
(-950 1125);
DISPLAY 0.617021 (-950 1125);
PAINT GREEN (-950 1125);
DISPLAY INVISIBLE (-950 1125);
FORCEPROP 2 LAST CDS_LIB w_hdl
R 1
J 0
(-950 1125);
DISPLAY INVISIBLE (-950 1125);
FORCEPROP 1 LAST CDS_LMAN_SYM_OUTLINE -50,75,50,-75
R 1
J 0
(-950 1125);
DISPLAY 0.468085 (-950 1125);
PAINT GREEN (-950 1125);
DISPLAY INVISIBLE (-950 1125);
FORCEADD 120R2F-GP..1
R 1
(-950 1075);
FORCEPROP 1 LAST LOCATION R25W39
J 0
(-1275 1075);
DISPLAY 0.617021 (-1275 1075);
PAINT GREEN (-1275 1075);
FORCEPROP 2 LAST RATED 1/16W
J 0
(-225 1075);
DISPLAY 0.638298 (-225 1075);
PAINT GREEN (-225 1075);
FORCEPROP 2 LAST ATTRIBUTE 120OHM
J 0
(-500 1075);
DISPLAY 0.638298 (-500 1075);
PAINT GREEN (-500 1075);
FORCEPROP 1 LAST VALUE 120R2F-GP
J 0
(-725 1075);
DISPLAY 0.617021 (-725 1075);
PAINT GREEN (-725 1075);
FORCEPROP 2 LASTPIN (-825 1075) $PN 2
J 0
(-815 1085);
DISPLAY 0.808511 (-815 1085);
PAINT ORANGE (-815 1085);
FORCEPROP 2 LASTPIN (-1075 1075) $PN 1
J 2
(-1060 1085);
DISPLAY 0.808511 (-1060 1085);
PAINT ORANGE (-1060 1085);
FORCEPROP 2 LAST TOLERANCE 1%
J 0
(-325 1075);
DISPLAY 0.638298 (-325 1075);
PAINT GREEN (-325 1075);
FORCEPROP 2 LAST PACK_SIZE 0402
J 0
(-50 1075);
DISPLAY 0.638298 (-50 1075);
PAINT GREEN (-50 1075);
FORCEPROP 1 LAST PATH I234
R 1
J 0
(-950 1075);
DISPLAY 0.617021 (-950 1075);
PAINT GREEN (-950 1075);
DISPLAY INVISIBLE (-950 1075);
FORCEPROP 1 LAST PACK_TYPE RCL_GP
R 1
J 0
(-950 1075);
DISPLAY 0.617021 (-950 1075);
PAINT GREEN (-950 1075);
DISPLAY INVISIBLE (-950 1075);
FORCEPROP 2 LAST SEC 1
J 0
(-725 1125);
DISPLAY 0.680851 (-725 1125);
PAINT MONO (-725 1125);
DISPLAY INVISIBLE (-725 1125);
FORCEPROP 2 LAST SEC_TYPE RCL_GP
J 0
(-725 1125);
DISPLAY 1.021277 (-725 1125);
PAINT ORANGE (-725 1125);
DISPLAY INVISIBLE (-725 1125);
FORCEPROP 1 LAST PART_NUMBER 64.12005.6DL
R 1
J 0
(-950 1075);
DISPLAY 0.617021 (-950 1075);
PAINT GREEN (-950 1075);
DISPLAY INVISIBLE (-950 1075);
FORCEPROP 2 LAST CDS_LIB w_hdl
R 1
J 0
(-950 1075);
DISPLAY INVISIBLE (-950 1075);
FORCEPROP 1 LAST CDS_LMAN_SYM_OUTLINE -50,75,50,-75
R 1
J 0
(-950 1075);
DISPLAY 0.468085 (-950 1075);
PAINT GREEN (-950 1075);
DISPLAY INVISIBLE (-950 1075);
FORCEADD 120R2F-GP..1
R 1
(-950 975);
FORCEPROP 1 LAST LOCATION R25W41
J 0
(-1275 975);
DISPLAY 0.617021 (-1275 975);
PAINT GREEN (-1275 975);
FORCEPROP 2 LAST ATTRIBUTE 120OHM
J 0
(-500 975);
DISPLAY 0.638298 (-500 975);
PAINT GREEN (-500 975);
FORCEPROP 1 LAST VALUE 120R2F-GP
J 0
(-725 975);
DISPLAY 0.617021 (-725 975);
PAINT GREEN (-725 975);
FORCEPROP 2 LASTPIN (-825 975) $PN 2
J 0
(-815 985);
DISPLAY 0.808511 (-815 985);
PAINT ORANGE (-815 985);
FORCEPROP 2 LAST TOLERANCE 1%
J 0
(-325 975);
DISPLAY 0.638298 (-325 975);
PAINT GREEN (-325 975);
FORCEPROP 2 LAST RATED 1/16W
J 0
(-225 975);
DISPLAY 0.638298 (-225 975);
PAINT GREEN (-225 975);
FORCEPROP 2 LASTPIN (-1075 975) $PN 1
J 2
(-1060 985);
DISPLAY 0.808511 (-1060 985);
PAINT ORANGE (-1060 985);
FORCEPROP 2 LAST PACK_SIZE 0402
J 0
(-50 975);
DISPLAY 0.638298 (-50 975);
PAINT GREEN (-50 975);
FORCEPROP 1 LAST PATH I235
R 1
J 0
(-950 975);
DISPLAY 0.617021 (-950 975);
PAINT GREEN (-950 975);
DISPLAY INVISIBLE (-950 975);
FORCEPROP 1 LAST CDS_LMAN_SYM_OUTLINE -50,75,50,-75
R 1
J 0
(-950 975);
DISPLAY 0.468085 (-950 975);
PAINT GREEN (-950 975);
DISPLAY INVISIBLE (-950 975);
FORCEPROP 2 LAST CDS_LIB w_hdl
R 1
J 0
(-950 975);
DISPLAY INVISIBLE (-950 975);
FORCEPROP 1 LAST PART_NUMBER 64.12005.6DL
R 1
J 0
(-950 975);
DISPLAY 0.617021 (-950 975);
PAINT GREEN (-950 975);
DISPLAY INVISIBLE (-950 975);
FORCEPROP 2 LAST SEC_TYPE RCL_GP
J 0
(-725 1025);
DISPLAY 1.021277 (-725 1025);
PAINT ORANGE (-725 1025);
DISPLAY INVISIBLE (-725 1025);
FORCEPROP 2 LAST SEC 1
J 0
(-725 1025);
DISPLAY 0.680851 (-725 1025);
PAINT MONO (-725 1025);
DISPLAY INVISIBLE (-725 1025);
FORCEPROP 1 LAST PACK_TYPE RCL_GP
R 1
J 0
(-950 975);
DISPLAY 0.617021 (-950 975);
PAINT GREEN (-950 975);
DISPLAY INVISIBLE (-950 975);
FORCEADD 120R2F-GP..1
R 1
(-950 925);
FORCEPROP 1 LAST LOCATION R25W42
J 0
(-1275 925);
DISPLAY 0.617021 (-1275 925);
PAINT GREEN (-1275 925);
FORCEPROP 2 LAST PACK_SIZE 0402
J 0
(-50 925);
DISPLAY 0.638298 (-50 925);
PAINT GREEN (-50 925);
FORCEPROP 2 LAST ATTRIBUTE 120OHM
J 0
(-500 925);
DISPLAY 0.638298 (-500 925);
PAINT GREEN (-500 925);
FORCEPROP 2 LAST TOLERANCE 1%
J 0
(-325 925);
DISPLAY 0.638298 (-325 925);
PAINT GREEN (-325 925);
FORCEPROP 1 LAST VALUE 120R2F-GP
J 0
(-725 925);
DISPLAY 0.617021 (-725 925);
PAINT GREEN (-725 925);
FORCEPROP 2 LASTPIN (-825 925) $PN 2
J 0
(-815 935);
DISPLAY 0.808511 (-815 935);
PAINT ORANGE (-815 935);
FORCEPROP 2 LASTPIN (-1075 925) $PN 1
J 2
(-1060 935);
DISPLAY 0.808511 (-1060 935);
PAINT ORANGE (-1060 935);
FORCEPROP 2 LAST RATED 1/16W
J 0
(-225 925);
DISPLAY 0.638298 (-225 925);
PAINT GREEN (-225 925);
FORCEPROP 1 LAST PATH I236
R 1
J 0
(-950 925);
DISPLAY 0.617021 (-950 925);
PAINT GREEN (-950 925);
DISPLAY INVISIBLE (-950 925);
FORCEPROP 1 LAST CDS_LMAN_SYM_OUTLINE -50,75,50,-75
R 1
J 0
(-950 925);
DISPLAY 0.468085 (-950 925);
PAINT GREEN (-950 925);
DISPLAY INVISIBLE (-950 925);
FORCEPROP 2 LAST CDS_LIB w_hdl
R 1
J 0
(-950 925);
DISPLAY INVISIBLE (-950 925);
FORCEPROP 1 LAST PART_NUMBER 64.12005.6DL
R 1
J 0
(-950 925);
DISPLAY 0.617021 (-950 925);
PAINT GREEN (-950 925);
DISPLAY INVISIBLE (-950 925);
FORCEPROP 2 LAST SEC_TYPE RCL_GP
J 0
(-725 975);
DISPLAY 1.021277 (-725 975);
PAINT ORANGE (-725 975);
DISPLAY INVISIBLE (-725 975);
FORCEPROP 2 LAST SEC 1
J 0
(-725 975);
DISPLAY 0.680851 (-725 975);
PAINT MONO (-725 975);
DISPLAY INVISIBLE (-725 975);
FORCEPROP 1 LAST PACK_TYPE RCL_GP
R 1
J 0
(-950 925);
DISPLAY 0.617021 (-950 925);
PAINT GREEN (-950 925);
DISPLAY INVISIBLE (-950 925);
FORCEADD 120R2F-GP..1
R 1
(-950 825);
FORCEPROP 1 LAST LOCATION R25W44
J 0
(-1275 825);
DISPLAY 0.617021 (-1275 825);
PAINT GREEN (-1275 825);
FORCEPROP 2 LAST PACK_SIZE 0402
J 0
(-50 825);
DISPLAY 0.638298 (-50 825);
PAINT GREEN (-50 825);
FORCEPROP 2 LAST RATED 1/16W
J 0
(-225 825);
DISPLAY 0.638298 (-225 825);
PAINT GREEN (-225 825);
FORCEPROP 1 LAST VALUE 120R2F-GP
J 0
(-725 825);
DISPLAY 0.617021 (-725 825);
PAINT GREEN (-725 825);
FORCEPROP 2 LAST ATTRIBUTE 120OHM
J 0
(-500 825);
DISPLAY 0.638298 (-500 825);
PAINT GREEN (-500 825);
FORCEPROP 2 LASTPIN (-825 825) $PN 2
J 0
(-815 835);
DISPLAY 0.808511 (-815 835);
PAINT ORANGE (-815 835);
FORCEPROP 2 LAST TOLERANCE 1%
J 0
(-325 825);
DISPLAY 0.638298 (-325 825);
PAINT GREEN (-325 825);
FORCEPROP 2 LASTPIN (-1075 825) $PN 1
J 2
(-1060 835);
DISPLAY 0.808511 (-1060 835);
PAINT ORANGE (-1060 835);
FORCEPROP 1 LAST PATH I237
R 1
J 0
(-950 825);
DISPLAY 0.617021 (-950 825);
PAINT GREEN (-950 825);
DISPLAY INVISIBLE (-950 825);
FORCEPROP 1 LAST CDS_LMAN_SYM_OUTLINE -50,75,50,-75
R 1
J 0
(-950 825);
DISPLAY 0.468085 (-950 825);
PAINT GREEN (-950 825);
DISPLAY INVISIBLE (-950 825);
FORCEPROP 2 LAST CDS_LIB w_hdl
R 1
J 0
(-950 825);
DISPLAY INVISIBLE (-950 825);
FORCEPROP 1 LAST PART_NUMBER 64.12005.6DL
R 1
J 0
(-950 825);
DISPLAY 0.617021 (-950 825);
PAINT GREEN (-950 825);
DISPLAY INVISIBLE (-950 825);
FORCEPROP 2 LAST SEC_TYPE RCL_GP
J 0
(-725 875);
DISPLAY 1.021277 (-725 875);
PAINT ORANGE (-725 875);
DISPLAY INVISIBLE (-725 875);
FORCEPROP 2 LAST SEC 1
J 0
(-725 875);
DISPLAY 0.680851 (-725 875);
PAINT MONO (-725 875);
DISPLAY INVISIBLE (-725 875);
FORCEPROP 1 LAST PACK_TYPE RCL_GP
R 1
J 0
(-950 825);
DISPLAY 0.617021 (-950 825);
PAINT GREEN (-950 825);
DISPLAY INVISIBLE (-950 825);
FORCEADD 120R2F-GP..1
R 1
(-950 875);
FORCEPROP 1 LAST LOCATION R25W43
J 0
(-1275 875);
DISPLAY 0.617021 (-1275 875);
PAINT GREEN (-1275 875);
FORCEPROP 2 LAST PACK_SIZE 0402
J 0
(-50 875);
DISPLAY 0.638298 (-50 875);
PAINT GREEN (-50 875);
FORCEPROP 1 LAST VALUE 120R2F-GP
J 0
(-725 875);
DISPLAY 0.617021 (-725 875);
PAINT GREEN (-725 875);
FORCEPROP 2 LAST ATTRIBUTE 120OHM
J 0
(-500 875);
DISPLAY 0.638298 (-500 875);
PAINT GREEN (-500 875);
FORCEPROP 2 LASTPIN (-825 875) $PN 2
J 0
(-815 885);
DISPLAY 0.808511 (-815 885);
PAINT ORANGE (-815 885);
FORCEPROP 2 LAST TOLERANCE 1%
J 0
(-325 875);
DISPLAY 0.638298 (-325 875);
PAINT GREEN (-325 875);
FORCEPROP 2 LAST RATED 1/16W
J 0
(-225 875);
DISPLAY 0.638298 (-225 875);
PAINT GREEN (-225 875);
FORCEPROP 2 LASTPIN (-1075 875) $PN 1
J 2
(-1060 885);
DISPLAY 0.808511 (-1060 885);
PAINT ORANGE (-1060 885);
FORCEPROP 1 LAST PATH I238
R 1
J 0
(-950 875);
DISPLAY 0.617021 (-950 875);
PAINT GREEN (-950 875);
DISPLAY INVISIBLE (-950 875);
FORCEPROP 1 LAST CDS_LMAN_SYM_OUTLINE -50,75,50,-75
R 1
J 0
(-950 875);
DISPLAY 0.468085 (-950 875);
PAINT GREEN (-950 875);
DISPLAY INVISIBLE (-950 875);
FORCEPROP 2 LAST CDS_LIB w_hdl
R 1
J 0
(-950 875);
DISPLAY INVISIBLE (-950 875);
FORCEPROP 1 LAST PART_NUMBER 64.12005.6DL
R 1
J 0
(-950 875);
DISPLAY 0.617021 (-950 875);
PAINT GREEN (-950 875);
DISPLAY INVISIBLE (-950 875);
FORCEPROP 2 LAST SEC_TYPE RCL_GP
J 0
(-725 925);
DISPLAY 1.021277 (-725 925);
PAINT ORANGE (-725 925);
DISPLAY INVISIBLE (-725 925);
FORCEPROP 2 LAST SEC 1
J 0
(-725 925);
DISPLAY 0.680851 (-725 925);
PAINT MONO (-725 925);
DISPLAY INVISIBLE (-725 925);
FORCEPROP 1 LAST PACK_TYPE RCL_GP
R 1
J 0
(-950 875);
DISPLAY 0.617021 (-950 875);
PAINT GREEN (-950 875);
DISPLAY INVISIBLE (-950 875);
FORCEADD 120R2F-GP..1
R 1
(-950 675);
FORCEPROP 1 LAST LOCATION R25W47
J 0
(-1275 675);
DISPLAY 0.617021 (-1275 675);
PAINT GREEN (-1275 675);
FORCEPROP 2 LAST PACK_SIZE 0402
J 0
(-50 675);
DISPLAY 0.638298 (-50 675);
PAINT GREEN (-50 675);
FORCEPROP 2 LAST ATTRIBUTE 120OHM
J 0
(-500 675);
DISPLAY 0.638298 (-500 675);
PAINT GREEN (-500 675);
FORCEPROP 2 LASTPIN (-825 675) $PN 2
J 0
(-815 685);
DISPLAY 0.808511 (-815 685);
PAINT ORANGE (-815 685);
FORCEPROP 1 LAST VALUE 120R2F-GP
J 0
(-725 675);
DISPLAY 0.617021 (-725 675);
PAINT GREEN (-725 675);
FORCEPROP 2 LAST TOLERANCE 1%
J 0
(-325 675);
DISPLAY 0.638298 (-325 675);
PAINT GREEN (-325 675);
FORCEPROP 2 LAST RATED 1/16W
J 0
(-225 675);
DISPLAY 0.638298 (-225 675);
PAINT GREEN (-225 675);
FORCEPROP 2 LASTPIN (-1075 675) $PN 1
J 2
(-1060 685);
DISPLAY 0.808511 (-1060 685);
PAINT ORANGE (-1060 685);
FORCEPROP 1 LAST PATH I239
R 1
J 0
(-950 675);
DISPLAY 0.617021 (-950 675);
PAINT GREEN (-950 675);
DISPLAY INVISIBLE (-950 675);
FORCEPROP 1 LAST CDS_LMAN_SYM_OUTLINE -50,75,50,-75
R 1
J 0
(-950 675);
DISPLAY 0.468085 (-950 675);
PAINT GREEN (-950 675);
DISPLAY INVISIBLE (-950 675);
FORCEPROP 2 LAST CDS_LIB w_hdl
R 1
J 0
(-950 675);
DISPLAY INVISIBLE (-950 675);
FORCEPROP 1 LAST PART_NUMBER 64.12005.6DL
R 1
J 0
(-950 675);
DISPLAY 0.617021 (-950 675);
PAINT GREEN (-950 675);
DISPLAY INVISIBLE (-950 675);
FORCEPROP 2 LAST SEC_TYPE RCL_GP
J 0
(-725 725);
DISPLAY 1.021277 (-725 725);
PAINT ORANGE (-725 725);
DISPLAY INVISIBLE (-725 725);
FORCEPROP 2 LAST SEC 1
J 0
(-725 725);
DISPLAY 0.680851 (-725 725);
PAINT MONO (-725 725);
DISPLAY INVISIBLE (-725 725);
FORCEPROP 1 LAST PACK_TYPE RCL_GP
R 1
J 0
(-950 675);
DISPLAY 0.617021 (-950 675);
PAINT GREEN (-950 675);
DISPLAY INVISIBLE (-950 675);
FORCEADD 120R2F-GP..1
R 1
(-950 625);
FORCEPROP 2 LAST PACK_SIZE 0402
J 0
(-50 625);
DISPLAY 0.638298 (-50 625);
PAINT GREEN (-50 625);
FORCEPROP 2 LAST ATTRIBUTE 120OHM
J 0
(-500 625);
DISPLAY 0.638298 (-500 625);
PAINT GREEN (-500 625);
FORCEPROP 2 LAST TOLERANCE 1%
J 0
(-325 625);
DISPLAY 0.638298 (-325 625);
PAINT GREEN (-325 625);
FORCEPROP 2 LAST RATED 1/16W
J 0
(-225 625);
DISPLAY 0.638298 (-225 625);
PAINT GREEN (-225 625);
FORCEPROP 1 LAST VALUE 120R2F-GP
J 0
(-725 625);
DISPLAY 0.617021 (-725 625);
PAINT GREEN (-725 625);
FORCEPROP 2 LASTPIN (-825 625) $PN 2
J 0
(-815 635);
DISPLAY 0.808511 (-815 635);
PAINT ORANGE (-815 635);
FORCEPROP 1 LAST LOCATION R25W48
J 0
(-1275 625);
DISPLAY 0.617021 (-1275 625);
PAINT GREEN (-1275 625);
FORCEPROP 2 LASTPIN (-1075 625) $PN 1
J 2
(-1060 635);
DISPLAY 0.808511 (-1060 635);
PAINT ORANGE (-1060 635);
FORCEPROP 1 LAST PATH I240
R 1
J 0
(-950 625);
DISPLAY 0.617021 (-950 625);
PAINT GREEN (-950 625);
DISPLAY INVISIBLE (-950 625);
FORCEPROP 1 LAST CDS_LMAN_SYM_OUTLINE -50,75,50,-75
R 1
J 0
(-950 625);
DISPLAY 0.468085 (-950 625);
PAINT GREEN (-950 625);
DISPLAY INVISIBLE (-950 625);
FORCEPROP 2 LAST CDS_LIB w_hdl
R 1
J 0
(-950 625);
DISPLAY INVISIBLE (-950 625);
FORCEPROP 1 LAST PART_NUMBER 64.12005.6DL
R 1
J 0
(-950 625);
DISPLAY 0.617021 (-950 625);
PAINT GREEN (-950 625);
DISPLAY INVISIBLE (-950 625);
FORCEPROP 2 LAST SEC_TYPE RCL_GP
J 0
(-725 675);
DISPLAY 1.021277 (-725 675);
PAINT ORANGE (-725 675);
DISPLAY INVISIBLE (-725 675);
FORCEPROP 2 LAST SEC 1
J 0
(-725 675);
DISPLAY 0.680851 (-725 675);
PAINT MONO (-725 675);
DISPLAY INVISIBLE (-725 675);
FORCEPROP 1 LAST PACK_TYPE RCL_GP
R 1
J 0
(-950 625);
DISPLAY 0.617021 (-950 625);
PAINT GREEN (-950 625);
DISPLAY INVISIBLE (-950 625);
FORCEADD 120R2F-GP..1
R 1
(-950 725);
FORCEPROP 1 LAST LOCATION R25W46
J 0
(-1275 725);
DISPLAY 0.617021 (-1275 725);
PAINT GREEN (-1275 725);
FORCEPROP 2 LAST PACK_SIZE 0402
J 0
(-50 725);
DISPLAY 0.638298 (-50 725);
PAINT GREEN (-50 725);
FORCEPROP 2 LASTPIN (-825 725) $PN 2
J 0
(-815 735);
DISPLAY 0.808511 (-815 735);
PAINT ORANGE (-815 735);
FORCEPROP 2 LAST TOLERANCE 1%
J 0
(-325 725);
DISPLAY 0.638298 (-325 725);
PAINT GREEN (-325 725);
FORCEPROP 2 LAST RATED 1/16W
J 0
(-225 725);
DISPLAY 0.638298 (-225 725);
PAINT GREEN (-225 725);
FORCEPROP 2 LASTPIN (-1075 725) $PN 1
J 2
(-1060 735);
DISPLAY 0.808511 (-1060 735);
PAINT ORANGE (-1060 735);
FORCEPROP 1 LAST VALUE 120R2F-GP
J 0
(-725 725);
DISPLAY 0.617021 (-725 725);
PAINT GREEN (-725 725);
FORCEPROP 2 LAST ATTRIBUTE 120OHM
J 0
(-500 725);
DISPLAY 0.638298 (-500 725);
PAINT GREEN (-500 725);
FORCEPROP 1 LAST PATH I241
R 1
J 0
(-950 725);
DISPLAY 0.617021 (-950 725);
PAINT GREEN (-950 725);
DISPLAY INVISIBLE (-950 725);
FORCEPROP 1 LAST CDS_LMAN_SYM_OUTLINE -50,75,50,-75
R 1
J 0
(-950 725);
DISPLAY 0.468085 (-950 725);
PAINT GREEN (-950 725);
DISPLAY INVISIBLE (-950 725);
FORCEPROP 2 LAST CDS_LIB w_hdl
R 1
J 0
(-950 725);
DISPLAY INVISIBLE (-950 725);
FORCEPROP 1 LAST PART_NUMBER 64.12005.6DL
R 1
J 0
(-950 725);
DISPLAY 0.617021 (-950 725);
PAINT GREEN (-950 725);
DISPLAY INVISIBLE (-950 725);
FORCEPROP 2 LAST SEC_TYPE RCL_GP
J 0
(-725 775);
DISPLAY 1.021277 (-725 775);
PAINT ORANGE (-725 775);
DISPLAY INVISIBLE (-725 775);
FORCEPROP 2 LAST SEC 1
J 0
(-725 775);
DISPLAY 0.680851 (-725 775);
PAINT MONO (-725 775);
DISPLAY INVISIBLE (-725 775);
FORCEPROP 1 LAST PACK_TYPE RCL_GP
R 1
J 0
(-950 725);
DISPLAY 0.617021 (-950 725);
PAINT GREEN (-950 725);
DISPLAY INVISIBLE (-950 725);
FORCEADD 120R2F-GP..1
R 1
(-950 775);
FORCEPROP 1 LAST LOCATION R25W45
J 0
(-1275 775);
DISPLAY 0.617021 (-1275 775);
PAINT GREEN (-1275 775);
FORCEPROP 1 LAST VALUE 120R2F-GP
J 0
(-725 775);
DISPLAY 0.617021 (-725 775);
PAINT GREEN (-725 775);
FORCEPROP 2 LASTPIN (-825 775) $PN 2
J 0
(-815 785);
DISPLAY 0.808511 (-815 785);
PAINT ORANGE (-815 785);
FORCEPROP 2 LAST ATTRIBUTE 120OHM
J 0
(-500 775);
DISPLAY 0.638298 (-500 775);
PAINT GREEN (-500 775);
FORCEPROP 2 LAST TOLERANCE 1%
J 0
(-325 775);
DISPLAY 0.638298 (-325 775);
PAINT GREEN (-325 775);
FORCEPROP 2 LASTPIN (-1075 775) $PN 1
J 2
(-1060 785);
DISPLAY 0.808511 (-1060 785);
PAINT ORANGE (-1060 785);
FORCEPROP 2 LAST RATED 1/16W
J 0
(-225 775);
DISPLAY 0.638298 (-225 775);
PAINT GREEN (-225 775);
FORCEPROP 2 LAST PACK_SIZE 0402
J 0
(-50 775);
DISPLAY 0.638298 (-50 775);
PAINT GREEN (-50 775);
FORCEPROP 1 LAST PATH I242
R 1
J 0
(-950 775);
DISPLAY 0.617021 (-950 775);
PAINT GREEN (-950 775);
DISPLAY INVISIBLE (-950 775);
FORCEPROP 1 LAST CDS_LMAN_SYM_OUTLINE -50,75,50,-75
R 1
J 0
(-950 775);
DISPLAY 0.468085 (-950 775);
PAINT GREEN (-950 775);
DISPLAY INVISIBLE (-950 775);
FORCEPROP 2 LAST CDS_LIB w_hdl
R 1
J 0
(-950 775);
DISPLAY INVISIBLE (-950 775);
FORCEPROP 1 LAST PART_NUMBER 64.12005.6DL
R 1
J 0
(-950 775);
DISPLAY 0.617021 (-950 775);
PAINT GREEN (-950 775);
DISPLAY INVISIBLE (-950 775);
FORCEPROP 2 LAST SEC_TYPE RCL_GP
J 0
(-725 825);
DISPLAY 1.021277 (-725 825);
PAINT ORANGE (-725 825);
DISPLAY INVISIBLE (-725 825);
FORCEPROP 2 LAST SEC 1
J 0
(-725 825);
DISPLAY 0.680851 (-725 825);
PAINT MONO (-725 825);
DISPLAY INVISIBLE (-725 825);
FORCEPROP 1 LAST PACK_TYPE RCL_GP
R 1
J 0
(-950 775);
DISPLAY 0.617021 (-950 775);
PAINT GREEN (-950 775);
DISPLAY INVISIBLE (-950 775);
FORCEADD 120R2F-GP..1
R 1
(-950 575);
FORCEPROP 2 LAST PACK_SIZE 0402
J 0
(-50 575);
DISPLAY 0.638298 (-50 575);
PAINT GREEN (-50 575);
FORCEPROP 1 LAST LOCATION R25W49
J 0
(-1275 575);
DISPLAY 0.617021 (-1275 575);
PAINT GREEN (-1275 575);
FORCEPROP 2 LASTPIN (-825 575) $PN 2
J 0
(-815 585);
DISPLAY 0.808511 (-815 585);
PAINT ORANGE (-815 585);
FORCEPROP 2 LASTPIN (-1075 575) $PN 1
J 2
(-1060 585);
DISPLAY 0.808511 (-1060 585);
PAINT ORANGE (-1060 585);
FORCEPROP 2 LAST TOLERANCE 1%
J 0
(-325 575);
DISPLAY 0.638298 (-325 575);
PAINT GREEN (-325 575);
FORCEPROP 2 LAST RATED 1/16W
J 0
(-225 575);
DISPLAY 0.638298 (-225 575);
PAINT GREEN (-225 575);
FORCEPROP 2 LAST ATTRIBUTE 120OHM
J 0
(-500 575);
DISPLAY 0.638298 (-500 575);
PAINT GREEN (-500 575);
FORCEPROP 1 LAST VALUE 120R2F-GP
J 0
(-725 575);
DISPLAY 0.617021 (-725 575);
PAINT GREEN (-725 575);
FORCEPROP 1 LAST PATH I243
R 1
J 0
(-950 575);
DISPLAY 0.617021 (-950 575);
PAINT GREEN (-950 575);
DISPLAY INVISIBLE (-950 575);
FORCEPROP 1 LAST CDS_LMAN_SYM_OUTLINE -50,75,50,-75
R 1
J 0
(-950 575);
DISPLAY 0.468085 (-950 575);
PAINT GREEN (-950 575);
DISPLAY INVISIBLE (-950 575);
FORCEPROP 2 LAST CDS_LIB w_hdl
R 1
J 0
(-950 575);
DISPLAY INVISIBLE (-950 575);
FORCEPROP 1 LAST PART_NUMBER 64.12005.6DL
R 1
J 0
(-950 575);
DISPLAY 0.617021 (-950 575);
PAINT GREEN (-950 575);
DISPLAY INVISIBLE (-950 575);
FORCEPROP 2 LAST SEC_TYPE RCL_GP
J 0
(-725 625);
DISPLAY 1.021277 (-725 625);
PAINT ORANGE (-725 625);
DISPLAY INVISIBLE (-725 625);
FORCEPROP 2 LAST SEC 1
J 0
(-725 625);
DISPLAY 0.680851 (-725 625);
PAINT MONO (-725 625);
DISPLAY INVISIBLE (-725 625);
FORCEPROP 1 LAST PACK_TYPE RCL_GP
R 1
J 0
(-950 575);
DISPLAY 0.617021 (-950 575);
PAINT GREEN (-950 575);
DISPLAY INVISIBLE (-950 575);
FORCEADD 120R2F-GP..1
R 1
(-950 525);
FORCEPROP 2 LAST PACK_SIZE 0402
J 0
(-50 525);
DISPLAY 0.638298 (-50 525);
PAINT GREEN (-50 525);
FORCEPROP 1 LAST LOCATION R25W50
J 0
(-1275 525);
DISPLAY 0.617021 (-1275 525);
PAINT GREEN (-1275 525);
FORCEPROP 2 LASTPIN (-825 525) $PN 2
J 0
(-815 535);
DISPLAY 0.808511 (-815 535);
PAINT ORANGE (-815 535);
FORCEPROP 2 LAST RATED 1/16W
J 0
(-225 525);
DISPLAY 0.638298 (-225 525);
PAINT GREEN (-225 525);
FORCEPROP 2 LASTPIN (-1075 525) $PN 1
J 2
(-1060 535);
DISPLAY 0.808511 (-1060 535);
PAINT ORANGE (-1060 535);
FORCEPROP 1 LAST VALUE 120R2F-GP
J 0
(-725 525);
DISPLAY 0.617021 (-725 525);
PAINT GREEN (-725 525);
FORCEPROP 2 LAST ATTRIBUTE 120OHM
J 0
(-500 525);
DISPLAY 0.638298 (-500 525);
PAINT GREEN (-500 525);
FORCEPROP 2 LAST TOLERANCE 1%
J 0
(-325 525);
DISPLAY 0.638298 (-325 525);
PAINT GREEN (-325 525);
FORCEPROP 1 LAST PATH I244
R 1
J 0
(-950 525);
DISPLAY 0.617021 (-950 525);
PAINT GREEN (-950 525);
DISPLAY INVISIBLE (-950 525);
FORCEPROP 1 LAST CDS_LMAN_SYM_OUTLINE -50,75,50,-75
R 1
J 0
(-950 525);
DISPLAY 0.468085 (-950 525);
PAINT GREEN (-950 525);
DISPLAY INVISIBLE (-950 525);
FORCEPROP 2 LAST CDS_LIB w_hdl
R 1
J 0
(-950 525);
DISPLAY INVISIBLE (-950 525);
FORCEPROP 1 LAST PART_NUMBER 64.12005.6DL
R 1
J 0
(-950 525);
DISPLAY 0.617021 (-950 525);
PAINT GREEN (-950 525);
DISPLAY INVISIBLE (-950 525);
FORCEPROP 2 LAST SEC_TYPE RCL_GP
J 0
(-725 575);
DISPLAY 1.021277 (-725 575);
PAINT ORANGE (-725 575);
DISPLAY INVISIBLE (-725 575);
FORCEPROP 2 LAST SEC 1
J 0
(-725 575);
DISPLAY 0.680851 (-725 575);
PAINT MONO (-725 575);
DISPLAY INVISIBLE (-725 575);
FORCEPROP 1 LAST PACK_TYPE RCL_GP
R 1
J 0
(-950 525);
DISPLAY 0.617021 (-950 525);
PAINT GREEN (-950 525);
DISPLAY INVISIBLE (-950 525);
FORCEADD 120R2F-GP..1
R 1
(-950 475);
FORCEPROP 2 LAST ATTRIBUTE 120OHM
J 0
(-500 475);
DISPLAY 0.638298 (-500 475);
PAINT GREEN (-500 475);
FORCEPROP 1 LAST VALUE 120R2F-GP
J 0
(-725 475);
DISPLAY 0.617021 (-725 475);
PAINT GREEN (-725 475);
FORCEPROP 2 LASTPIN (-825 475) $PN 2
J 0
(-815 485);
DISPLAY 0.808511 (-815 485);
PAINT ORANGE (-815 485);
FORCEPROP 2 LAST TOLERANCE 1%
J 0
(-325 475);
DISPLAY 0.638298 (-325 475);
PAINT GREEN (-325 475);
FORCEPROP 2 LASTPIN (-1075 475) $PN 1
J 2
(-1060 485);
DISPLAY 0.808511 (-1060 485);
PAINT ORANGE (-1060 485);
FORCEPROP 1 LAST LOCATION R25W51
J 0
(-1275 475);
DISPLAY 0.617021 (-1275 475);
PAINT GREEN (-1275 475);
FORCEPROP 2 LAST RATED 1/16W
J 0
(-225 475);
DISPLAY 0.638298 (-225 475);
PAINT GREEN (-225 475);
FORCEPROP 2 LAST PACK_SIZE 0402
J 0
(-50 475);
DISPLAY 0.638298 (-50 475);
PAINT GREEN (-50 475);
FORCEPROP 1 LAST PATH I245
R 1
J 0
(-950 475);
DISPLAY 0.617021 (-950 475);
PAINT GREEN (-950 475);
DISPLAY INVISIBLE (-950 475);
FORCEPROP 1 LAST CDS_LMAN_SYM_OUTLINE -50,75,50,-75
R 1
J 0
(-950 475);
DISPLAY 0.468085 (-950 475);
PAINT GREEN (-950 475);
DISPLAY INVISIBLE (-950 475);
FORCEPROP 2 LAST CDS_LIB w_hdl
R 1
J 0
(-950 475);
DISPLAY INVISIBLE (-950 475);
FORCEPROP 1 LAST PART_NUMBER 64.12005.6DL
R 1
J 0
(-950 475);
DISPLAY 0.617021 (-950 475);
PAINT GREEN (-950 475);
DISPLAY INVISIBLE (-950 475);
FORCEPROP 2 LAST SEC_TYPE RCL_GP
J 0
(-725 525);
DISPLAY 1.021277 (-725 525);
PAINT ORANGE (-725 525);
DISPLAY INVISIBLE (-725 525);
FORCEPROP 2 LAST SEC 1
J 0
(-725 525);
DISPLAY 0.680851 (-725 525);
PAINT MONO (-725 525);
DISPLAY INVISIBLE (-725 525);
FORCEPROP 1 LAST PACK_TYPE RCL_GP
R 1
J 0
(-950 475);
DISPLAY 0.617021 (-950 475);
PAINT GREEN (-950 475);
DISPLAY INVISIBLE (-950 475);
FORCEADD 120R2F-GP..1
R 1
(-950 425);
FORCEPROP 2 LAST ATTRIBUTE 120OHM
J 0
(-500 425);
DISPLAY 0.638298 (-500 425);
PAINT GREEN (-500 425);
FORCEPROP 1 LAST VALUE 120R2F-GP
J 0
(-725 425);
DISPLAY 0.617021 (-725 425);
PAINT GREEN (-725 425);
FORCEPROP 2 LASTPIN (-825 425) $PN 2
J 0
(-815 435);
DISPLAY 0.808511 (-815 435);
PAINT ORANGE (-815 435);
FORCEPROP 2 LAST TOLERANCE 1%
J 0
(-325 425);
DISPLAY 0.638298 (-325 425);
PAINT GREEN (-325 425);
FORCEPROP 2 LAST RATED 1/16W
J 0
(-225 425);
DISPLAY 0.638298 (-225 425);
PAINT GREEN (-225 425);
FORCEPROP 2 LASTPIN (-1075 425) $PN 1
J 2
(-1060 435);
DISPLAY 0.808511 (-1060 435);
PAINT ORANGE (-1060 435);
FORCEPROP 1 LAST LOCATION R25W52
J 0
(-1275 425);
DISPLAY 0.617021 (-1275 425);
PAINT GREEN (-1275 425);
FORCEPROP 2 LAST PACK_SIZE 0402
J 0
(-50 425);
DISPLAY 0.638298 (-50 425);
PAINT GREEN (-50 425);
FORCEPROP 1 LAST PATH I246
R 1
J 0
(-950 425);
DISPLAY 0.617021 (-950 425);
PAINT GREEN (-950 425);
DISPLAY INVISIBLE (-950 425);
FORCEPROP 1 LAST CDS_LMAN_SYM_OUTLINE -50,75,50,-75
R 1
J 0
(-950 425);
DISPLAY 0.468085 (-950 425);
PAINT GREEN (-950 425);
DISPLAY INVISIBLE (-950 425);
FORCEPROP 2 LAST CDS_LIB w_hdl
R 1
J 0
(-950 425);
DISPLAY INVISIBLE (-950 425);
FORCEPROP 1 LAST PART_NUMBER 64.12005.6DL
R 1
J 0
(-950 425);
DISPLAY 0.617021 (-950 425);
PAINT GREEN (-950 425);
DISPLAY INVISIBLE (-950 425);
FORCEPROP 2 LAST SEC_TYPE RCL_GP
J 0
(-725 475);
DISPLAY 1.021277 (-725 475);
PAINT ORANGE (-725 475);
DISPLAY INVISIBLE (-725 475);
FORCEPROP 2 LAST SEC 1
J 0
(-725 475);
DISPLAY 0.680851 (-725 475);
PAINT MONO (-725 475);
DISPLAY INVISIBLE (-725 475);
FORCEPROP 1 LAST PACK_TYPE RCL_GP
R 1
J 0
(-950 425);
DISPLAY 0.617021 (-950 425);
PAINT GREEN (-950 425);
DISPLAY INVISIBLE (-950 425);
FORCEADD 120R2F-GP..1
R 1
(-950 1025);
FORCEPROP 1 LAST LOCATION R25W40
J 0
(-1275 1025);
DISPLAY 0.617021 (-1275 1025);
PAINT GREEN (-1275 1025);
FORCEPROP 2 LAST TOLERANCE 1%
J 0
(-325 1025);
DISPLAY 0.638298 (-325 1025);
PAINT GREEN (-325 1025);
FORCEPROP 2 LAST ATTRIBUTE 120OHM
J 0
(-500 1025);
DISPLAY 0.638298 (-500 1025);
PAINT GREEN (-500 1025);
FORCEPROP 1 LAST VALUE 120R2F-GP
J 0
(-725 1025);
DISPLAY 0.617021 (-725 1025);
PAINT GREEN (-725 1025);
FORCEPROP 2 LASTPIN (-825 1025) $PN 2
J 0
(-815 1035);
DISPLAY 0.808511 (-815 1035);
PAINT ORANGE (-815 1035);
FORCEPROP 2 LAST RATED 1/16W
J 0
(-225 1025);
DISPLAY 0.638298 (-225 1025);
PAINT GREEN (-225 1025);
FORCEPROP 2 LASTPIN (-1075 1025) $PN 1
J 2
(-1060 1035);
DISPLAY 0.808511 (-1060 1035);
PAINT ORANGE (-1060 1035);
FORCEPROP 2 LAST PACK_SIZE 0402
J 0
(-50 1025);
DISPLAY 0.638298 (-50 1025);
PAINT GREEN (-50 1025);
FORCEPROP 1 LAST PATH I247
R 1
J 0
(-950 1025);
DISPLAY 0.617021 (-950 1025);
PAINT GREEN (-950 1025);
DISPLAY INVISIBLE (-950 1025);
FORCEPROP 1 LAST CDS_LMAN_SYM_OUTLINE -50,75,50,-75
R 1
J 0
(-950 1025);
DISPLAY 0.468085 (-950 1025);
PAINT GREEN (-950 1025);
DISPLAY INVISIBLE (-950 1025);
FORCEPROP 2 LAST CDS_LIB w_hdl
R 1
J 0
(-950 1025);
DISPLAY INVISIBLE (-950 1025);
FORCEPROP 1 LAST PART_NUMBER 64.12005.6DL
R 1
J 0
(-950 1025);
DISPLAY 0.617021 (-950 1025);
PAINT GREEN (-950 1025);
DISPLAY INVISIBLE (-950 1025);
FORCEPROP 2 LAST SEC_TYPE RCL_GP
J 0
(-725 1075);
DISPLAY 1.021277 (-725 1075);
PAINT ORANGE (-725 1075);
DISPLAY INVISIBLE (-725 1075);
FORCEPROP 2 LAST SEC 1
J 0
(-725 1075);
DISPLAY 0.680851 (-725 1075);
PAINT MONO (-725 1075);
DISPLAY INVISIBLE (-725 1075);
FORCEPROP 1 LAST PACK_TYPE RCL_GP
R 1
J 0
(-950 1025);
DISPLAY 0.617021 (-950 1025);
PAINT GREEN (-950 1025);
DISPLAY INVISIBLE (-950 1025);
FORCEADD 120R2F-GP..1
R 1
(-3025 1675);
FORCEPROP 2 LASTPIN (-3150 1675) $PN 1
J 2
(-3135 1685);
DISPLAY 0.808511 (-3135 1685);
PAINT ORANGE (-3135 1685);
FORCEPROP 2 LAST ATTRIBUTE 120OHM
J 0
(-2575 1675);
DISPLAY 0.638298 (-2575 1675);
PAINT GREEN (-2575 1675);
FORCEPROP 2 LAST RATED 1/16W
J 0
(-2300 1675);
DISPLAY 0.638298 (-2300 1675);
PAINT GREEN (-2300 1675);
FORCEPROP 2 LAST TOLERANCE 1%
J 0
(-2400 1675);
DISPLAY 0.638298 (-2400 1675);
PAINT GREEN (-2400 1675);
FORCEPROP 2 LASTPIN (-2900 1675) $PN 2
J 0
(-2890 1685);
DISPLAY 0.808511 (-2890 1685);
PAINT ORANGE (-2890 1685);
FORCEPROP 1 LAST LOCATION R25W1
J 0
(-3350 1675);
DISPLAY 0.617021 (-3350 1675);
PAINT GREEN (-3350 1675);
FORCEPROP 2 LAST PACK_SIZE 0402
J 0
(-2150 1675);
DISPLAY 0.638298 (-2150 1675);
PAINT GREEN (-2150 1675);
FORCEPROP 1 LAST VALUE 120R2F-GP
J 0
(-2800 1675);
DISPLAY 0.617021 (-2800 1675);
PAINT GREEN (-2800 1675);
FORCEPROP 1 LAST CDS_LMAN_SYM_OUTLINE -50,75,50,-75
R 1
J 0
(-3025 1675);
DISPLAY 0.468085 (-3025 1675);
PAINT GREEN (-3025 1675);
DISPLAY INVISIBLE (-3025 1675);
FORCEPROP 2 LAST CDS_LIB w_hdl
R 1
J 0
(-3025 1675);
DISPLAY INVISIBLE (-3025 1675);
FORCEPROP 1 LAST PART_NUMBER 64.12005.6DL
R 1
J 0
(-3025 1675);
DISPLAY 0.617021 (-3025 1675);
PAINT GREEN (-3025 1675);
DISPLAY INVISIBLE (-3025 1675);
FORCEPROP 2 LAST SEC_TYPE RCL_GP
J 0
(-2800 1725);
DISPLAY 1.021277 (-2800 1725);
PAINT ORANGE (-2800 1725);
DISPLAY INVISIBLE (-2800 1725);
FORCEPROP 2 LAST SEC 1
J 0
(-2800 1725);
DISPLAY 0.680851 (-2800 1725);
PAINT MONO (-2800 1725);
DISPLAY INVISIBLE (-2800 1725);
FORCEPROP 1 LAST PACK_TYPE RCL_GP
R 1
J 0
(-3025 1675);
DISPLAY 0.617021 (-3025 1675);
PAINT GREEN (-3025 1675);
DISPLAY INVISIBLE (-3025 1675);
FORCEPROP 1 LAST PATH I248
R 1
J 0
(-3025 1675);
DISPLAY 0.617021 (-3025 1675);
PAINT GREEN (-3025 1675);
DISPLAY INVISIBLE (-3025 1675);
FORCEADD 120R2F-GP..1
R 1
(-3025 1625);
FORCEPROP 2 LAST ATTRIBUTE 120OHM
J 0
(-2575 1625);
DISPLAY 0.638298 (-2575 1625);
PAINT GREEN (-2575 1625);
FORCEPROP 2 LAST TOLERANCE 1%
J 0
(-2400 1625);
DISPLAY 0.638298 (-2400 1625);
PAINT GREEN (-2400 1625);
FORCEPROP 2 LAST RATED 1/16W
J 0
(-2300 1625);
DISPLAY 0.638298 (-2300 1625);
PAINT GREEN (-2300 1625);
FORCEPROP 2 LASTPIN (-3150 1625) $PN 1
J 2
(-3135 1635);
DISPLAY 0.808511 (-3135 1635);
PAINT ORANGE (-3135 1635);
FORCEPROP 2 LASTPIN (-2900 1625) $PN 2
J 0
(-2890 1635);
DISPLAY 0.808511 (-2890 1635);
PAINT ORANGE (-2890 1635);
FORCEPROP 1 LAST VALUE 120R2F-GP
J 0
(-2800 1625);
DISPLAY 0.617021 (-2800 1625);
PAINT GREEN (-2800 1625);
FORCEPROP 2 LAST PACK_SIZE 0402
J 0
(-2150 1625);
DISPLAY 0.638298 (-2150 1625);
PAINT GREEN (-2150 1625);
FORCEPROP 1 LAST LOCATION R25W2
J 0
(-3350 1625);
DISPLAY 0.617021 (-3350 1625);
PAINT GREEN (-3350 1625);
FORCEPROP 1 LAST PATH I249
R 1
J 0
(-3025 1625);
DISPLAY 0.617021 (-3025 1625);
PAINT GREEN (-3025 1625);
DISPLAY INVISIBLE (-3025 1625);
FORCEPROP 1 LAST PACK_TYPE RCL_GP
R 1
J 0
(-3025 1625);
DISPLAY 0.617021 (-3025 1625);
PAINT GREEN (-3025 1625);
DISPLAY INVISIBLE (-3025 1625);
FORCEPROP 2 LAST SEC 1
J 0
(-2800 1675);
DISPLAY 0.680851 (-2800 1675);
PAINT MONO (-2800 1675);
DISPLAY INVISIBLE (-2800 1675);
FORCEPROP 2 LAST SEC_TYPE RCL_GP
J 0
(-2800 1675);
DISPLAY 1.021277 (-2800 1675);
PAINT ORANGE (-2800 1675);
DISPLAY INVISIBLE (-2800 1675);
FORCEPROP 1 LAST PART_NUMBER 64.12005.6DL
R 1
J 0
(-3025 1625);
DISPLAY 0.617021 (-3025 1625);
PAINT GREEN (-3025 1625);
DISPLAY INVISIBLE (-3025 1625);
FORCEPROP 2 LAST CDS_LIB w_hdl
R 1
J 0
(-3025 1625);
DISPLAY INVISIBLE (-3025 1625);
FORCEPROP 1 LAST CDS_LMAN_SYM_OUTLINE -50,75,50,-75
R 1
J 0
(-3025 1625);
DISPLAY 0.468085 (-3025 1625);
PAINT GREEN (-3025 1625);
DISPLAY INVISIBLE (-3025 1625);
FORCEADD 120R2F-GP..1
R 1
(-3025 1575);
FORCEPROP 2 LASTPIN (-2900 1575) $PN 2
J 0
(-2890 1585);
DISPLAY 0.808511 (-2890 1585);
PAINT ORANGE (-2890 1585);
FORCEPROP 2 LAST TOLERANCE 1%
J 0
(-2400 1575);
DISPLAY 0.638298 (-2400 1575);
PAINT GREEN (-2400 1575);
FORCEPROP 0 LAST POP NOPOP
J 0
(-3125 1550);
DISPLAY 1.021277 (-3125 1550);
PAINT RED (-3125 1550);
FORCEPROP 2 LASTPIN (-3150 1575) $PN 1
J 2
(-3135 1585);
DISPLAY 0.808511 (-3135 1585);
PAINT ORANGE (-3135 1585);
FORCEPROP 1 LAST LOCATION R25W3
J 0
(-3350 1575);
DISPLAY 0.617021 (-3350 1575);
PAINT GREEN (-3350 1575);
FORCEPROP 2 LAST RATED 1/16W
J 0
(-2300 1575);
DISPLAY 0.638298 (-2300 1575);
PAINT GREEN (-2300 1575);
FORCEPROP 2 LAST ATTRIBUTE 120OHM
J 0
(-2575 1575);
DISPLAY 0.638298 (-2575 1575);
PAINT GREEN (-2575 1575);
FORCEPROP 1 LAST VALUE 120R2F-GP
J 0
(-2800 1575);
DISPLAY 0.617021 (-2800 1575);
PAINT GREEN (-2800 1575);
FORCEPROP 2 LAST PACK_SIZE 0402
J 0
(-2150 1575);
DISPLAY 0.638298 (-2150 1575);
PAINT GREEN (-2150 1575);
FORCEPROP 1 LAST PATH I250
R 1
J 0
(-3025 1575);
DISPLAY 0.617021 (-3025 1575);
PAINT GREEN (-3025 1575);
DISPLAY INVISIBLE (-3025 1575);
FORCEPROP 1 LAST PACK_TYPE RCL_GP
R 1
J 0
(-3025 1575);
DISPLAY 0.617021 (-3025 1575);
PAINT GREEN (-3025 1575);
DISPLAY INVISIBLE (-3025 1575);
FORCEPROP 2 LAST SEC 1
J 0
(-2800 1625);
DISPLAY 0.680851 (-2800 1625);
PAINT MONO (-2800 1625);
DISPLAY INVISIBLE (-2800 1625);
FORCEPROP 2 LAST SEC_TYPE RCL_GP
J 0
(-2800 1625);
DISPLAY 1.021277 (-2800 1625);
PAINT ORANGE (-2800 1625);
DISPLAY INVISIBLE (-2800 1625);
FORCEPROP 1 LAST PART_NUMBER 64.12005.6DL
R 1
J 0
(-3025 1575);
DISPLAY 0.617021 (-3025 1575);
PAINT GREEN (-3025 1575);
DISPLAY INVISIBLE (-3025 1575);
FORCEPROP 2 LAST CDS_LIB w_hdl
R 1
J 0
(-3025 1575);
DISPLAY INVISIBLE (-3025 1575);
FORCEPROP 1 LAST CDS_LMAN_SYM_OUTLINE -50,75,50,-75
R 1
J 0
(-3025 1575);
DISPLAY 0.468085 (-3025 1575);
PAINT GREEN (-3025 1575);
DISPLAY INVISIBLE (-3025 1575);
FORCEADD 120R2F-GP..1
R 1
(-3025 1525);
FORCEPROP 1 LAST VALUE 120R2F-GP
J 0
(-2800 1525);
DISPLAY 0.617021 (-2800 1525);
PAINT GREEN (-2800 1525);
FORCEPROP 2 LAST RATED 1/16W
J 0
(-2300 1525);
DISPLAY 0.638298 (-2300 1525);
PAINT GREEN (-2300 1525);
FORCEPROP 0 LAST POP NOPOP
J 0
(-3125 1500);
DISPLAY 1.021277 (-3125 1500);
PAINT RED (-3125 1500);
FORCEPROP 2 LASTPIN (-3150 1525) $PN 1
J 2
(-3135 1535);
DISPLAY 0.808511 (-3135 1535);
PAINT ORANGE (-3135 1535);
FORCEPROP 2 LASTPIN (-2900 1525) $PN 2
J 0
(-2890 1535);
DISPLAY 0.808511 (-2890 1535);
PAINT ORANGE (-2890 1535);
FORCEPROP 1 LAST LOCATION R25W4
J 0
(-3350 1525);
DISPLAY 0.617021 (-3350 1525);
PAINT GREEN (-3350 1525);
FORCEPROP 2 LAST TOLERANCE 1%
J 0
(-2400 1525);
DISPLAY 0.638298 (-2400 1525);
PAINT GREEN (-2400 1525);
FORCEPROP 2 LAST ATTRIBUTE 120OHM
J 0
(-2575 1525);
DISPLAY 0.638298 (-2575 1525);
PAINT GREEN (-2575 1525);
FORCEPROP 2 LAST PACK_SIZE 0402
J 0
(-2150 1525);
DISPLAY 0.638298 (-2150 1525);
PAINT GREEN (-2150 1525);
FORCEPROP 1 LAST PATH I251
R 1
J 0
(-3025 1525);
DISPLAY 0.617021 (-3025 1525);
PAINT GREEN (-3025 1525);
DISPLAY INVISIBLE (-3025 1525);
FORCEPROP 1 LAST PACK_TYPE RCL_GP
R 1
J 0
(-3025 1525);
DISPLAY 0.617021 (-3025 1525);
PAINT GREEN (-3025 1525);
DISPLAY INVISIBLE (-3025 1525);
FORCEPROP 2 LAST SEC 1
J 0
(-2800 1575);
DISPLAY 0.680851 (-2800 1575);
PAINT MONO (-2800 1575);
DISPLAY INVISIBLE (-2800 1575);
FORCEPROP 2 LAST SEC_TYPE RCL_GP
J 0
(-2800 1575);
DISPLAY 1.021277 (-2800 1575);
PAINT ORANGE (-2800 1575);
DISPLAY INVISIBLE (-2800 1575);
FORCEPROP 1 LAST PART_NUMBER 64.12005.6DL
R 1
J 0
(-3025 1525);
DISPLAY 0.617021 (-3025 1525);
PAINT GREEN (-3025 1525);
DISPLAY INVISIBLE (-3025 1525);
FORCEPROP 2 LAST CDS_LIB w_hdl
R 1
J 0
(-3025 1525);
DISPLAY INVISIBLE (-3025 1525);
FORCEPROP 1 LAST CDS_LMAN_SYM_OUTLINE -50,75,50,-75
R 1
J 0
(-3025 1525);
DISPLAY 0.468085 (-3025 1525);
PAINT GREEN (-3025 1525);
DISPLAY INVISIBLE (-3025 1525);
FORCEADD 120R2F-GP..1
R 1
(-3025 1475);
FORCEPROP 1 LAST VALUE 120R2F-GP
J 0
(-2800 1475);
DISPLAY 0.617021 (-2800 1475);
PAINT GREEN (-2800 1475);
FORCEPROP 2 LAST RATED 1/16W
J 0
(-2300 1475);
DISPLAY 0.638298 (-2300 1475);
PAINT GREEN (-2300 1475);
FORCEPROP 1 LAST LOCATION R25W5
J 0
(-3350 1475);
DISPLAY 0.617021 (-3350 1475);
PAINT GREEN (-3350 1475);
FORCEPROP 2 LASTPIN (-2900 1475) $PN 2
J 0
(-2890 1485);
DISPLAY 0.808511 (-2890 1485);
PAINT ORANGE (-2890 1485);
FORCEPROP 2 LAST TOLERANCE 1%
J 0
(-2400 1475);
DISPLAY 0.638298 (-2400 1475);
PAINT GREEN (-2400 1475);
FORCEPROP 2 LASTPIN (-3150 1475) $PN 1
J 2
(-3135 1485);
DISPLAY 0.808511 (-3135 1485);
PAINT ORANGE (-3135 1485);
FORCEPROP 2 LAST ATTRIBUTE 120OHM
J 0
(-2575 1475);
DISPLAY 0.638298 (-2575 1475);
PAINT GREEN (-2575 1475);
FORCEPROP 2 LAST PACK_SIZE 0402
J 0
(-2150 1475);
DISPLAY 0.638298 (-2150 1475);
PAINT GREEN (-2150 1475);
FORCEPROP 1 LAST PATH I252
R 1
J 0
(-3025 1475);
DISPLAY 0.617021 (-3025 1475);
PAINT GREEN (-3025 1475);
DISPLAY INVISIBLE (-3025 1475);
FORCEPROP 1 LAST CDS_LMAN_SYM_OUTLINE -50,75,50,-75
R 1
J 0
(-3025 1475);
DISPLAY 0.468085 (-3025 1475);
PAINT GREEN (-3025 1475);
DISPLAY INVISIBLE (-3025 1475);
FORCEPROP 2 LAST CDS_LIB w_hdl
R 1
J 0
(-3025 1475);
DISPLAY INVISIBLE (-3025 1475);
FORCEPROP 1 LAST PART_NUMBER 64.12005.6DL
R 1
J 0
(-3025 1475);
DISPLAY 0.617021 (-3025 1475);
PAINT GREEN (-3025 1475);
DISPLAY INVISIBLE (-3025 1475);
FORCEPROP 2 LAST SEC_TYPE RCL_GP
J 0
(-2800 1525);
DISPLAY 1.021277 (-2800 1525);
PAINT ORANGE (-2800 1525);
DISPLAY INVISIBLE (-2800 1525);
FORCEPROP 2 LAST SEC 1
J 0
(-2800 1525);
DISPLAY 0.680851 (-2800 1525);
PAINT MONO (-2800 1525);
DISPLAY INVISIBLE (-2800 1525);
FORCEPROP 1 LAST PACK_TYPE RCL_GP
R 1
J 0
(-3025 1475);
DISPLAY 0.617021 (-3025 1475);
PAINT GREEN (-3025 1475);
DISPLAY INVISIBLE (-3025 1475);
FORCEADD 120R2F-GP..1
R 1
(-3025 1425);
FORCEPROP 2 LAST RATED 1/16W
J 0
(-2300 1425);
DISPLAY 0.638298 (-2300 1425);
PAINT GREEN (-2300 1425);
FORCEPROP 1 LAST LOCATION R25W6
J 0
(-3350 1425);
DISPLAY 0.617021 (-3350 1425);
PAINT GREEN (-3350 1425);
FORCEPROP 1 LAST VALUE 120R2F-GP
J 0
(-2800 1425);
DISPLAY 0.617021 (-2800 1425);
PAINT GREEN (-2800 1425);
FORCEPROP 2 LASTPIN (-2900 1425) $PN 2
J 0
(-2890 1435);
DISPLAY 0.808511 (-2890 1435);
PAINT ORANGE (-2890 1435);
FORCEPROP 2 LAST TOLERANCE 1%
J 0
(-2400 1425);
DISPLAY 0.638298 (-2400 1425);
PAINT GREEN (-2400 1425);
FORCEPROP 2 LASTPIN (-3150 1425) $PN 1
J 2
(-3135 1435);
DISPLAY 0.808511 (-3135 1435);
PAINT ORANGE (-3135 1435);
FORCEPROP 2 LAST ATTRIBUTE 120OHM
J 0
(-2575 1425);
DISPLAY 0.638298 (-2575 1425);
PAINT GREEN (-2575 1425);
FORCEPROP 2 LAST PACK_SIZE 0402
J 0
(-2150 1425);
DISPLAY 0.638298 (-2150 1425);
PAINT GREEN (-2150 1425);
FORCEPROP 1 LAST PATH I253
R 1
J 0
(-3025 1425);
DISPLAY 0.617021 (-3025 1425);
PAINT GREEN (-3025 1425);
DISPLAY INVISIBLE (-3025 1425);
FORCEPROP 1 LAST CDS_LMAN_SYM_OUTLINE -50,75,50,-75
R 1
J 0
(-3025 1425);
DISPLAY 0.468085 (-3025 1425);
PAINT GREEN (-3025 1425);
DISPLAY INVISIBLE (-3025 1425);
FORCEPROP 2 LAST CDS_LIB w_hdl
R 1
J 0
(-3025 1425);
DISPLAY INVISIBLE (-3025 1425);
FORCEPROP 1 LAST PART_NUMBER 64.12005.6DL
R 1
J 0
(-3025 1425);
DISPLAY 0.617021 (-3025 1425);
PAINT GREEN (-3025 1425);
DISPLAY INVISIBLE (-3025 1425);
FORCEPROP 2 LAST SEC_TYPE RCL_GP
J 0
(-2800 1475);
DISPLAY 1.021277 (-2800 1475);
PAINT ORANGE (-2800 1475);
DISPLAY INVISIBLE (-2800 1475);
FORCEPROP 2 LAST SEC 1
J 0
(-2800 1475);
DISPLAY 0.680851 (-2800 1475);
PAINT MONO (-2800 1475);
DISPLAY INVISIBLE (-2800 1475);
FORCEPROP 1 LAST PACK_TYPE RCL_GP
R 1
J 0
(-3025 1425);
DISPLAY 0.617021 (-3025 1425);
PAINT GREEN (-3025 1425);
DISPLAY INVISIBLE (-3025 1425);
FORCEADD 120R2F-GP..1
R 1
(-3025 1375);
FORCEPROP 2 LAST RATED 1/16W
J 0
(-2300 1375);
DISPLAY 0.638298 (-2300 1375);
PAINT GREEN (-2300 1375);
FORCEPROP 2 LAST TOLERANCE 1%
J 0
(-2400 1375);
DISPLAY 0.638298 (-2400 1375);
PAINT GREEN (-2400 1375);
FORCEPROP 1 LAST LOCATION R25W7
J 0
(-3350 1375);
DISPLAY 0.617021 (-3350 1375);
PAINT GREEN (-3350 1375);
FORCEPROP 1 LAST VALUE 120R2F-GP
J 0
(-2800 1375);
DISPLAY 0.617021 (-2800 1375);
PAINT GREEN (-2800 1375);
FORCEPROP 2 LASTPIN (-2900 1375) $PN 2
J 0
(-2890 1385);
DISPLAY 0.808511 (-2890 1385);
PAINT ORANGE (-2890 1385);
FORCEPROP 2 LASTPIN (-3150 1375) $PN 1
J 2
(-3135 1385);
DISPLAY 0.808511 (-3135 1385);
PAINT ORANGE (-3135 1385);
FORCEPROP 2 LAST ATTRIBUTE 120OHM
J 0
(-2575 1375);
DISPLAY 0.638298 (-2575 1375);
PAINT GREEN (-2575 1375);
FORCEPROP 2 LAST PACK_SIZE 0402
J 0
(-2150 1375);
DISPLAY 0.638298 (-2150 1375);
PAINT GREEN (-2150 1375);
FORCEPROP 1 LAST PATH I254
R 1
J 0
(-3025 1375);
DISPLAY 0.617021 (-3025 1375);
PAINT GREEN (-3025 1375);
DISPLAY INVISIBLE (-3025 1375);
FORCEPROP 1 LAST CDS_LMAN_SYM_OUTLINE -50,75,50,-75
R 1
J 0
(-3025 1375);
DISPLAY 0.468085 (-3025 1375);
PAINT GREEN (-3025 1375);
DISPLAY INVISIBLE (-3025 1375);
FORCEPROP 2 LAST CDS_LIB w_hdl
R 1
J 0
(-3025 1375);
DISPLAY INVISIBLE (-3025 1375);
FORCEPROP 1 LAST PART_NUMBER 64.12005.6DL
R 1
J 0
(-3025 1375);
DISPLAY 0.617021 (-3025 1375);
PAINT GREEN (-3025 1375);
DISPLAY INVISIBLE (-3025 1375);
FORCEPROP 2 LAST SEC_TYPE RCL_GP
J 0
(-2800 1425);
DISPLAY 1.021277 (-2800 1425);
PAINT ORANGE (-2800 1425);
DISPLAY INVISIBLE (-2800 1425);
FORCEPROP 2 LAST SEC 1
J 0
(-2800 1425);
DISPLAY 0.680851 (-2800 1425);
PAINT MONO (-2800 1425);
DISPLAY INVISIBLE (-2800 1425);
FORCEPROP 1 LAST PACK_TYPE RCL_GP
R 1
J 0
(-3025 1375);
DISPLAY 0.617021 (-3025 1375);
PAINT GREEN (-3025 1375);
DISPLAY INVISIBLE (-3025 1375);
FORCEADD 120R2F-GP..1
R 1
(-3025 1325);
FORCEPROP 2 LAST ATTRIBUTE 120OHM
J 0
(-2575 1325);
DISPLAY 0.638298 (-2575 1325);
PAINT GREEN (-2575 1325);
FORCEPROP 2 LAST RATED 1/16W
J 0
(-2300 1325);
DISPLAY 0.638298 (-2300 1325);
PAINT GREEN (-2300 1325);
FORCEPROP 1 LAST LOCATION R25W8
J 0
(-3350 1325);
DISPLAY 0.617021 (-3350 1325);
PAINT GREEN (-3350 1325);
FORCEPROP 1 LAST VALUE 120R2F-GP
J 0
(-2800 1325);
DISPLAY 0.617021 (-2800 1325);
PAINT GREEN (-2800 1325);
FORCEPROP 2 LASTPIN (-2900 1325) $PN 2
J 0
(-2890 1335);
DISPLAY 0.808511 (-2890 1335);
PAINT ORANGE (-2890 1335);
FORCEPROP 2 LASTPIN (-3150 1325) $PN 1
J 2
(-3135 1335);
DISPLAY 0.808511 (-3135 1335);
PAINT ORANGE (-3135 1335);
FORCEPROP 2 LAST TOLERANCE 1%
J 0
(-2400 1325);
DISPLAY 0.638298 (-2400 1325);
PAINT GREEN (-2400 1325);
FORCEPROP 2 LAST PACK_SIZE 0402
J 0
(-2150 1325);
DISPLAY 0.638298 (-2150 1325);
PAINT GREEN (-2150 1325);
FORCEPROP 1 LAST PATH I255
R 1
J 0
(-3025 1325);
DISPLAY 0.617021 (-3025 1325);
PAINT GREEN (-3025 1325);
DISPLAY INVISIBLE (-3025 1325);
FORCEPROP 1 LAST CDS_LMAN_SYM_OUTLINE -50,75,50,-75
R 1
J 0
(-3025 1325);
DISPLAY 0.468085 (-3025 1325);
PAINT GREEN (-3025 1325);
DISPLAY INVISIBLE (-3025 1325);
FORCEPROP 2 LAST CDS_LIB w_hdl
R 1
J 0
(-3025 1325);
DISPLAY INVISIBLE (-3025 1325);
FORCEPROP 1 LAST PART_NUMBER 64.12005.6DL
R 1
J 0
(-3025 1325);
DISPLAY 0.617021 (-3025 1325);
PAINT GREEN (-3025 1325);
DISPLAY INVISIBLE (-3025 1325);
FORCEPROP 2 LAST SEC_TYPE RCL_GP
J 0
(-2800 1375);
DISPLAY 1.021277 (-2800 1375);
PAINT ORANGE (-2800 1375);
DISPLAY INVISIBLE (-2800 1375);
FORCEPROP 2 LAST SEC 1
J 0
(-2800 1375);
DISPLAY 0.680851 (-2800 1375);
PAINT MONO (-2800 1375);
DISPLAY INVISIBLE (-2800 1375);
FORCEPROP 1 LAST PACK_TYPE RCL_GP
R 1
J 0
(-3025 1325);
DISPLAY 0.617021 (-3025 1325);
PAINT GREEN (-3025 1325);
DISPLAY INVISIBLE (-3025 1325);
FORCEADD 120R2F-GP..1
R 1
(-3025 1125);
FORCEPROP 2 LAST ATTRIBUTE 120OHM
J 0
(-2575 1125);
DISPLAY 0.638298 (-2575 1125);
PAINT GREEN (-2575 1125);
FORCEPROP 2 LAST TOLERANCE 1%
J 0
(-2400 1125);
DISPLAY 0.638298 (-2400 1125);
PAINT GREEN (-2400 1125);
FORCEPROP 1 LAST VALUE 120R2F-GP
J 0
(-2800 1125);
DISPLAY 0.617021 (-2800 1125);
PAINT GREEN (-2800 1125);
FORCEPROP 1 LAST LOCATION R25W12
J 0
(-3350 1125);
DISPLAY 0.617021 (-3350 1125);
PAINT GREEN (-3350 1125);
FORCEPROP 2 LASTPIN (-2900 1125) $PN 2
J 0
(-2890 1135);
DISPLAY 0.808511 (-2890 1135);
PAINT ORANGE (-2890 1135);
FORCEPROP 2 LASTPIN (-3150 1125) $PN 1
J 2
(-3135 1135);
DISPLAY 0.808511 (-3135 1135);
PAINT ORANGE (-3135 1135);
FORCEPROP 2 LAST RATED 1/16W
J 0
(-2300 1125);
DISPLAY 0.638298 (-2300 1125);
PAINT GREEN (-2300 1125);
FORCEPROP 2 LAST PACK_SIZE 0402
J 0
(-2150 1125);
DISPLAY 0.638298 (-2150 1125);
PAINT GREEN (-2150 1125);
FORCEPROP 1 LAST PATH I256
R 1
J 0
(-3025 1125);
DISPLAY 0.617021 (-3025 1125);
PAINT GREEN (-3025 1125);
DISPLAY INVISIBLE (-3025 1125);
FORCEPROP 1 LAST CDS_LMAN_SYM_OUTLINE -50,75,50,-75
R 1
J 0
(-3025 1125);
DISPLAY 0.468085 (-3025 1125);
PAINT GREEN (-3025 1125);
DISPLAY INVISIBLE (-3025 1125);
FORCEPROP 2 LAST CDS_LIB w_hdl
R 1
J 0
(-3025 1125);
DISPLAY INVISIBLE (-3025 1125);
FORCEPROP 1 LAST PART_NUMBER 64.12005.6DL
R 1
J 0
(-3025 1125);
DISPLAY 0.617021 (-3025 1125);
PAINT GREEN (-3025 1125);
DISPLAY INVISIBLE (-3025 1125);
FORCEPROP 2 LAST SEC_TYPE RCL_GP
J 0
(-2800 1175);
DISPLAY 1.021277 (-2800 1175);
PAINT ORANGE (-2800 1175);
DISPLAY INVISIBLE (-2800 1175);
FORCEPROP 2 LAST SEC 1
J 0
(-2800 1175);
DISPLAY 0.680851 (-2800 1175);
PAINT MONO (-2800 1175);
DISPLAY INVISIBLE (-2800 1175);
FORCEPROP 1 LAST PACK_TYPE RCL_GP
R 1
J 0
(-3025 1125);
DISPLAY 0.617021 (-3025 1125);
PAINT GREEN (-3025 1125);
DISPLAY INVISIBLE (-3025 1125);
FORCEADD 120R2F-GP..1
R 1
(-3025 1175);
FORCEPROP 2 LAST ATTRIBUTE 120OHM
J 0
(-2575 1175);
DISPLAY 0.638298 (-2575 1175);
PAINT GREEN (-2575 1175);
FORCEPROP 2 LASTPIN (-2900 1175) $PN 2
J 0
(-2890 1185);
DISPLAY 0.808511 (-2890 1185);
PAINT ORANGE (-2890 1185);
FORCEPROP 2 LAST RATED 1/16W
J 0
(-2300 1175);
DISPLAY 0.638298 (-2300 1175);
PAINT GREEN (-2300 1175);
FORCEPROP 1 LAST VALUE 120R2F-GP
J 0
(-2800 1175);
DISPLAY 0.617021 (-2800 1175);
PAINT GREEN (-2800 1175);
FORCEPROP 1 LAST LOCATION R25W11
J 0
(-3350 1175);
DISPLAY 0.617021 (-3350 1175);
PAINT GREEN (-3350 1175);
FORCEPROP 2 LAST TOLERANCE 1%
J 0
(-2400 1175);
DISPLAY 0.638298 (-2400 1175);
PAINT GREEN (-2400 1175);
FORCEPROP 2 LASTPIN (-3150 1175) $PN 1
J 2
(-3135 1185);
DISPLAY 0.808511 (-3135 1185);
PAINT ORANGE (-3135 1185);
FORCEPROP 2 LAST PACK_SIZE 0402
J 0
(-2150 1175);
DISPLAY 0.638298 (-2150 1175);
PAINT GREEN (-2150 1175);
FORCEPROP 1 LAST PATH I257
R 1
J 0
(-3025 1175);
DISPLAY 0.617021 (-3025 1175);
PAINT GREEN (-3025 1175);
DISPLAY INVISIBLE (-3025 1175);
FORCEPROP 1 LAST CDS_LMAN_SYM_OUTLINE -50,75,50,-75
R 1
J 0
(-3025 1175);
DISPLAY 0.468085 (-3025 1175);
PAINT GREEN (-3025 1175);
DISPLAY INVISIBLE (-3025 1175);
FORCEPROP 2 LAST CDS_LIB w_hdl
R 1
J 0
(-3025 1175);
DISPLAY INVISIBLE (-3025 1175);
FORCEPROP 1 LAST PART_NUMBER 64.12005.6DL
R 1
J 0
(-3025 1175);
DISPLAY 0.617021 (-3025 1175);
PAINT GREEN (-3025 1175);
DISPLAY INVISIBLE (-3025 1175);
FORCEPROP 2 LAST SEC_TYPE RCL_GP
J 0
(-2800 1225);
DISPLAY 1.021277 (-2800 1225);
PAINT ORANGE (-2800 1225);
DISPLAY INVISIBLE (-2800 1225);
FORCEPROP 2 LAST SEC 1
J 0
(-2800 1225);
DISPLAY 0.680851 (-2800 1225);
PAINT MONO (-2800 1225);
DISPLAY INVISIBLE (-2800 1225);
FORCEPROP 1 LAST PACK_TYPE RCL_GP
R 1
J 0
(-3025 1175);
DISPLAY 0.617021 (-3025 1175);
PAINT GREEN (-3025 1175);
DISPLAY INVISIBLE (-3025 1175);
FORCEADD 120R2F-GP..1
R 1
(-3025 1275);
FORCEPROP 2 LAST ATTRIBUTE 120OHM
J 0
(-2575 1275);
DISPLAY 0.638298 (-2575 1275);
PAINT GREEN (-2575 1275);
FORCEPROP 1 LAST LOCATION R25W9
J 0
(-3350 1275);
DISPLAY 0.617021 (-3350 1275);
PAINT GREEN (-3350 1275);
FORCEPROP 1 LAST VALUE 120R2F-GP
J 0
(-2800 1275);
DISPLAY 0.617021 (-2800 1275);
PAINT GREEN (-2800 1275);
FORCEPROP 2 LASTPIN (-2900 1275) $PN 2
J 0
(-2890 1285);
DISPLAY 0.808511 (-2890 1285);
PAINT ORANGE (-2890 1285);
FORCEPROP 2 LASTPIN (-3150 1275) $PN 1
J 2
(-3135 1285);
DISPLAY 0.808511 (-3135 1285);
PAINT ORANGE (-3135 1285);
FORCEPROP 2 LAST TOLERANCE 1%
J 0
(-2400 1275);
DISPLAY 0.638298 (-2400 1275);
PAINT GREEN (-2400 1275);
FORCEPROP 2 LAST RATED 1/16W
J 0
(-2300 1275);
DISPLAY 0.638298 (-2300 1275);
PAINT GREEN (-2300 1275);
FORCEPROP 2 LAST PACK_SIZE 0402
J 0
(-2150 1275);
DISPLAY 0.638298 (-2150 1275);
PAINT GREEN (-2150 1275);
FORCEPROP 1 LAST PATH I258
R 1
J 0
(-3025 1275);
DISPLAY 0.617021 (-3025 1275);
PAINT GREEN (-3025 1275);
DISPLAY INVISIBLE (-3025 1275);
FORCEPROP 1 LAST CDS_LMAN_SYM_OUTLINE -50,75,50,-75
R 1
J 0
(-3025 1275);
DISPLAY 0.468085 (-3025 1275);
PAINT GREEN (-3025 1275);
DISPLAY INVISIBLE (-3025 1275);
FORCEPROP 2 LAST CDS_LIB w_hdl
R 1
J 0
(-3025 1275);
DISPLAY INVISIBLE (-3025 1275);
FORCEPROP 1 LAST PART_NUMBER 64.12005.6DL
R 1
J 0
(-3025 1275);
DISPLAY 0.617021 (-3025 1275);
PAINT GREEN (-3025 1275);
DISPLAY INVISIBLE (-3025 1275);
FORCEPROP 2 LAST SEC_TYPE RCL_GP
J 0
(-2800 1325);
DISPLAY 1.021277 (-2800 1325);
PAINT ORANGE (-2800 1325);
DISPLAY INVISIBLE (-2800 1325);
FORCEPROP 2 LAST SEC 1
J 0
(-2800 1325);
DISPLAY 0.680851 (-2800 1325);
PAINT MONO (-2800 1325);
DISPLAY INVISIBLE (-2800 1325);
FORCEPROP 1 LAST PACK_TYPE RCL_GP
R 1
J 0
(-3025 1275);
DISPLAY 0.617021 (-3025 1275);
PAINT GREEN (-3025 1275);
DISPLAY INVISIBLE (-3025 1275);
FORCEADD 120R2F-GP..1
R 1
(-3025 1225);
FORCEPROP 2 LAST ATTRIBUTE 120OHM
J 0
(-2575 1225);
DISPLAY 0.638298 (-2575 1225);
PAINT GREEN (-2575 1225);
FORCEPROP 1 LAST LOCATION R25W10
J 0
(-3350 1225);
DISPLAY 0.617021 (-3350 1225);
PAINT GREEN (-3350 1225);
FORCEPROP 1 LAST VALUE 120R2F-GP
J 0
(-2800 1225);
DISPLAY 0.617021 (-2800 1225);
PAINT GREEN (-2800 1225);
FORCEPROP 2 LASTPIN (-2900 1225) $PN 2
J 0
(-2890 1235);
DISPLAY 0.808511 (-2890 1235);
PAINT ORANGE (-2890 1235);
FORCEPROP 2 LAST TOLERANCE 1%
J 0
(-2400 1225);
DISPLAY 0.638298 (-2400 1225);
PAINT GREEN (-2400 1225);
FORCEPROP 2 LASTPIN (-3150 1225) $PN 1
J 2
(-3135 1235);
DISPLAY 0.808511 (-3135 1235);
PAINT ORANGE (-3135 1235);
FORCEPROP 2 LAST RATED 1/16W
J 0
(-2300 1225);
DISPLAY 0.638298 (-2300 1225);
PAINT GREEN (-2300 1225);
FORCEPROP 2 LAST PACK_SIZE 0402
J 0
(-2150 1225);
DISPLAY 0.638298 (-2150 1225);
PAINT GREEN (-2150 1225);
FORCEPROP 1 LAST PATH I259
R 1
J 0
(-3025 1225);
DISPLAY 0.617021 (-3025 1225);
PAINT GREEN (-3025 1225);
DISPLAY INVISIBLE (-3025 1225);
FORCEPROP 1 LAST CDS_LMAN_SYM_OUTLINE -50,75,50,-75
R 1
J 0
(-3025 1225);
DISPLAY 0.468085 (-3025 1225);
PAINT GREEN (-3025 1225);
DISPLAY INVISIBLE (-3025 1225);
FORCEPROP 2 LAST CDS_LIB w_hdl
R 1
J 0
(-3025 1225);
DISPLAY INVISIBLE (-3025 1225);
FORCEPROP 1 LAST PART_NUMBER 64.12005.6DL
R 1
J 0
(-3025 1225);
DISPLAY 0.617021 (-3025 1225);
PAINT GREEN (-3025 1225);
DISPLAY INVISIBLE (-3025 1225);
FORCEPROP 2 LAST SEC_TYPE RCL_GP
J 0
(-2800 1275);
DISPLAY 1.021277 (-2800 1275);
PAINT ORANGE (-2800 1275);
DISPLAY INVISIBLE (-2800 1275);
FORCEPROP 2 LAST SEC 1
J 0
(-2800 1275);
DISPLAY 0.680851 (-2800 1275);
PAINT MONO (-2800 1275);
DISPLAY INVISIBLE (-2800 1275);
FORCEPROP 1 LAST PACK_TYPE RCL_GP
R 1
J 0
(-3025 1225);
DISPLAY 0.617021 (-3025 1225);
PAINT GREEN (-3025 1225);
DISPLAY INVISIBLE (-3025 1225);
FORCEADD 120R2F-GP..1
R 1
(-3025 1075);
FORCEPROP 2 LAST ATTRIBUTE 120OHM
J 0
(-2575 1075);
DISPLAY 0.638298 (-2575 1075);
PAINT GREEN (-2575 1075);
FORCEPROP 2 LAST TOLERANCE 1%
J 0
(-2400 1075);
DISPLAY 0.638298 (-2400 1075);
PAINT GREEN (-2400 1075);
FORCEPROP 1 LAST VALUE 120R2F-GP
J 0
(-2800 1075);
DISPLAY 0.617021 (-2800 1075);
PAINT GREEN (-2800 1075);
FORCEPROP 1 LAST LOCATION R25W13
J 0
(-3350 1075);
DISPLAY 0.617021 (-3350 1075);
PAINT GREEN (-3350 1075);
FORCEPROP 2 LASTPIN (-2900 1075) $PN 2
J 0
(-2890 1085);
DISPLAY 0.808511 (-2890 1085);
PAINT ORANGE (-2890 1085);
FORCEPROP 2 LAST RATED 1/16W
J 0
(-2300 1075);
DISPLAY 0.638298 (-2300 1075);
PAINT GREEN (-2300 1075);
FORCEPROP 2 LASTPIN (-3150 1075) $PN 1
J 2
(-3135 1085);
DISPLAY 0.808511 (-3135 1085);
PAINT ORANGE (-3135 1085);
FORCEPROP 2 LAST PACK_SIZE 0402
J 0
(-2150 1075);
DISPLAY 0.638298 (-2150 1075);
PAINT GREEN (-2150 1075);
FORCEPROP 1 LAST PATH I260
R 1
J 0
(-3025 1075);
DISPLAY 0.617021 (-3025 1075);
PAINT GREEN (-3025 1075);
DISPLAY INVISIBLE (-3025 1075);
FORCEPROP 1 LAST CDS_LMAN_SYM_OUTLINE -50,75,50,-75
R 1
J 0
(-3025 1075);
DISPLAY 0.468085 (-3025 1075);
PAINT GREEN (-3025 1075);
DISPLAY INVISIBLE (-3025 1075);
FORCEPROP 2 LAST CDS_LIB w_hdl
R 1
J 0
(-3025 1075);
DISPLAY INVISIBLE (-3025 1075);
FORCEPROP 1 LAST PART_NUMBER 64.12005.6DL
R 1
J 0
(-3025 1075);
DISPLAY 0.617021 (-3025 1075);
PAINT GREEN (-3025 1075);
DISPLAY INVISIBLE (-3025 1075);
FORCEPROP 2 LAST SEC_TYPE RCL_GP
J 0
(-2800 1125);
DISPLAY 1.021277 (-2800 1125);
PAINT ORANGE (-2800 1125);
DISPLAY INVISIBLE (-2800 1125);
FORCEPROP 2 LAST SEC 1
J 0
(-2800 1125);
DISPLAY 0.680851 (-2800 1125);
PAINT MONO (-2800 1125);
DISPLAY INVISIBLE (-2800 1125);
FORCEPROP 1 LAST PACK_TYPE RCL_GP
R 1
J 0
(-3025 1075);
DISPLAY 0.617021 (-3025 1075);
PAINT GREEN (-3025 1075);
DISPLAY INVISIBLE (-3025 1075);
FORCEADD 120R2F-GP..1
R 1
(-3025 925);
FORCEPROP 2 LAST ATTRIBUTE 120OHM
J 0
(-2575 925);
DISPLAY 0.638298 (-2575 925);
PAINT GREEN (-2575 925);
FORCEPROP 2 LAST RATED 1/16W
J 0
(-2300 925);
DISPLAY 0.638298 (-2300 925);
PAINT GREEN (-2300 925);
FORCEPROP 2 LASTPIN (-3150 925) $PN 1
J 2
(-3135 935);
DISPLAY 0.808511 (-3135 935);
PAINT ORANGE (-3135 935);
FORCEPROP 2 LAST TOLERANCE 1%
J 0
(-2400 925);
DISPLAY 0.638298 (-2400 925);
PAINT GREEN (-2400 925);
FORCEPROP 2 LASTPIN (-2900 925) $PN 2
J 0
(-2890 935);
DISPLAY 0.808511 (-2890 935);
PAINT ORANGE (-2890 935);
FORCEPROP 1 LAST VALUE 120R2F-GP
J 0
(-2800 925);
DISPLAY 0.617021 (-2800 925);
PAINT GREEN (-2800 925);
FORCEPROP 1 LAST LOCATION R25W16
J 0
(-3350 925);
DISPLAY 0.617021 (-3350 925);
PAINT GREEN (-3350 925);
FORCEPROP 2 LAST PACK_SIZE 0402
J 0
(-2150 925);
DISPLAY 0.638298 (-2150 925);
PAINT GREEN (-2150 925);
FORCEPROP 1 LAST PACK_TYPE RCL_GP
R 1
J 0
(-3025 925);
DISPLAY 0.617021 (-3025 925);
PAINT GREEN (-3025 925);
DISPLAY INVISIBLE (-3025 925);
FORCEPROP 2 LAST SEC 1
J 0
(-2800 975);
DISPLAY 0.680851 (-2800 975);
PAINT MONO (-2800 975);
DISPLAY INVISIBLE (-2800 975);
FORCEPROP 2 LAST SEC_TYPE RCL_GP
J 0
(-2800 975);
DISPLAY 1.021277 (-2800 975);
PAINT ORANGE (-2800 975);
DISPLAY INVISIBLE (-2800 975);
FORCEPROP 1 LAST PART_NUMBER 64.12005.6DL
R 1
J 0
(-3025 925);
DISPLAY 0.617021 (-3025 925);
PAINT GREEN (-3025 925);
DISPLAY INVISIBLE (-3025 925);
FORCEPROP 2 LAST CDS_LIB w_hdl
R 1
J 0
(-3025 925);
DISPLAY INVISIBLE (-3025 925);
FORCEPROP 1 LAST CDS_LMAN_SYM_OUTLINE -50,75,50,-75
R 1
J 0
(-3025 925);
DISPLAY 0.468085 (-3025 925);
PAINT GREEN (-3025 925);
DISPLAY INVISIBLE (-3025 925);
FORCEPROP 1 LAST PATH I261
R 1
J 0
(-3025 925);
DISPLAY 0.617021 (-3025 925);
PAINT GREEN (-3025 925);
DISPLAY INVISIBLE (-3025 925);
FORCEADD 120R2F-GP..1
R 1
(-3025 975);
FORCEPROP 2 LAST ATTRIBUTE 120OHM
J 0
(-2575 975);
DISPLAY 0.638298 (-2575 975);
PAINT GREEN (-2575 975);
FORCEPROP 2 LAST RATED 1/16W
J 0
(-2300 975);
DISPLAY 0.638298 (-2300 975);
PAINT GREEN (-2300 975);
FORCEPROP 2 LAST TOLERANCE 1%
J 0
(-2400 975);
DISPLAY 0.638298 (-2400 975);
PAINT GREEN (-2400 975);
FORCEPROP 1 LAST VALUE 120R2F-GP
J 0
(-2800 975);
DISPLAY 0.617021 (-2800 975);
PAINT GREEN (-2800 975);
FORCEPROP 2 LASTPIN (-2900 975) $PN 2
J 0
(-2890 985);
DISPLAY 0.808511 (-2890 985);
PAINT ORANGE (-2890 985);
FORCEPROP 1 LAST LOCATION R25W15
J 0
(-3350 975);
DISPLAY 0.617021 (-3350 975);
PAINT GREEN (-3350 975);
FORCEPROP 2 LASTPIN (-3150 975) $PN 1
J 2
(-3135 985);
DISPLAY 0.808511 (-3135 985);
PAINT ORANGE (-3135 985);
FORCEPROP 2 LAST PACK_SIZE 0402
J 0
(-2150 975);
DISPLAY 0.638298 (-2150 975);
PAINT GREEN (-2150 975);
FORCEPROP 1 LAST PATH I262
R 1
J 0
(-3025 975);
DISPLAY 0.617021 (-3025 975);
PAINT GREEN (-3025 975);
DISPLAY INVISIBLE (-3025 975);
FORCEPROP 1 LAST CDS_LMAN_SYM_OUTLINE -50,75,50,-75
R 1
J 0
(-3025 975);
DISPLAY 0.468085 (-3025 975);
PAINT GREEN (-3025 975);
DISPLAY INVISIBLE (-3025 975);
FORCEPROP 2 LAST CDS_LIB w_hdl
R 1
J 0
(-3025 975);
DISPLAY INVISIBLE (-3025 975);
FORCEPROP 1 LAST PART_NUMBER 64.12005.6DL
R 1
J 0
(-3025 975);
DISPLAY 0.617021 (-3025 975);
PAINT GREEN (-3025 975);
DISPLAY INVISIBLE (-3025 975);
FORCEPROP 2 LAST SEC_TYPE RCL_GP
J 0
(-2800 1025);
DISPLAY 1.021277 (-2800 1025);
PAINT ORANGE (-2800 1025);
DISPLAY INVISIBLE (-2800 1025);
FORCEPROP 2 LAST SEC 1
J 0
(-2800 1025);
DISPLAY 0.680851 (-2800 1025);
PAINT MONO (-2800 1025);
DISPLAY INVISIBLE (-2800 1025);
FORCEPROP 1 LAST PACK_TYPE RCL_GP
R 1
J 0
(-3025 975);
DISPLAY 0.617021 (-3025 975);
PAINT GREEN (-3025 975);
DISPLAY INVISIBLE (-3025 975);
FORCEADD 120R2F-GP..1
R 1
(-3025 1025);
FORCEPROP 2 LAST ATTRIBUTE 120OHM
J 0
(-2575 1025);
DISPLAY 0.638298 (-2575 1025);
PAINT GREEN (-2575 1025);
FORCEPROP 2 LAST TOLERANCE 1%
J 0
(-2400 1025);
DISPLAY 0.638298 (-2400 1025);
PAINT GREEN (-2400 1025);
FORCEPROP 1 LAST VALUE 120R2F-GP
J 0
(-2800 1025);
DISPLAY 0.617021 (-2800 1025);
PAINT GREEN (-2800 1025);
FORCEPROP 1 LAST LOCATION R25W14
J 0
(-3350 1025);
DISPLAY 0.617021 (-3350 1025);
PAINT GREEN (-3350 1025);
FORCEPROP 2 LASTPIN (-2900 1025) $PN 2
J 0
(-2890 1035);
DISPLAY 0.808511 (-2890 1035);
PAINT ORANGE (-2890 1035);
FORCEPROP 2 LAST RATED 1/16W
J 0
(-2300 1025);
DISPLAY 0.638298 (-2300 1025);
PAINT GREEN (-2300 1025);
FORCEPROP 2 LASTPIN (-3150 1025) $PN 1
J 2
(-3135 1035);
DISPLAY 0.808511 (-3135 1035);
PAINT ORANGE (-3135 1035);
FORCEPROP 2 LAST PACK_SIZE 0402
J 0
(-2150 1025);
DISPLAY 0.638298 (-2150 1025);
PAINT GREEN (-2150 1025);
FORCEPROP 1 LAST PATH I263
R 1
J 0
(-3025 1025);
DISPLAY 0.617021 (-3025 1025);
PAINT GREEN (-3025 1025);
DISPLAY INVISIBLE (-3025 1025);
FORCEPROP 1 LAST CDS_LMAN_SYM_OUTLINE -50,75,50,-75
R 1
J 0
(-3025 1025);
DISPLAY 0.468085 (-3025 1025);
PAINT GREEN (-3025 1025);
DISPLAY INVISIBLE (-3025 1025);
FORCEPROP 2 LAST CDS_LIB w_hdl
R 1
J 0
(-3025 1025);
DISPLAY INVISIBLE (-3025 1025);
FORCEPROP 1 LAST PART_NUMBER 64.12005.6DL
R 1
J 0
(-3025 1025);
DISPLAY 0.617021 (-3025 1025);
PAINT GREEN (-3025 1025);
DISPLAY INVISIBLE (-3025 1025);
FORCEPROP 2 LAST SEC_TYPE RCL_GP
J 0
(-2800 1075);
DISPLAY 1.021277 (-2800 1075);
PAINT ORANGE (-2800 1075);
DISPLAY INVISIBLE (-2800 1075);
FORCEPROP 2 LAST SEC 1
J 0
(-2800 1075);
DISPLAY 0.680851 (-2800 1075);
PAINT MONO (-2800 1075);
DISPLAY INVISIBLE (-2800 1075);
FORCEPROP 1 LAST PACK_TYPE RCL_GP
R 1
J 0
(-3025 1025);
DISPLAY 0.617021 (-3025 1025);
PAINT GREEN (-3025 1025);
DISPLAY INVISIBLE (-3025 1025);
FORCEADD 120R2F-GP..1
R 1
(-3025 875);
FORCEPROP 2 LAST ATTRIBUTE 120OHM
J 0
(-2575 875);
DISPLAY 0.638298 (-2575 875);
PAINT GREEN (-2575 875);
FORCEPROP 1 LAST LOCATION R25W17
J 0
(-3350 875);
DISPLAY 0.617021 (-3350 875);
PAINT GREEN (-3350 875);
FORCEPROP 2 LASTPIN (-3150 875) $PN 1
J 2
(-3135 885);
DISPLAY 0.808511 (-3135 885);
PAINT ORANGE (-3135 885);
FORCEPROP 2 LAST RATED 1/16W
J 0
(-2300 875);
DISPLAY 0.638298 (-2300 875);
PAINT GREEN (-2300 875);
FORCEPROP 2 LAST TOLERANCE 1%
J 0
(-2400 875);
DISPLAY 0.638298 (-2400 875);
PAINT GREEN (-2400 875);
FORCEPROP 2 LASTPIN (-2900 875) $PN 2
J 0
(-2890 885);
DISPLAY 0.808511 (-2890 885);
PAINT ORANGE (-2890 885);
FORCEPROP 1 LAST VALUE 120R2F-GP
J 0
(-2800 875);
DISPLAY 0.617021 (-2800 875);
PAINT GREEN (-2800 875);
FORCEPROP 2 LAST PACK_SIZE 0402
J 0
(-2150 875);
DISPLAY 0.638298 (-2150 875);
PAINT GREEN (-2150 875);
FORCEPROP 1 LAST PATH I264
R 1
J 0
(-3025 875);
DISPLAY 0.617021 (-3025 875);
PAINT GREEN (-3025 875);
DISPLAY INVISIBLE (-3025 875);
FORCEPROP 1 LAST PACK_TYPE RCL_GP
R 1
J 0
(-3025 875);
DISPLAY 0.617021 (-3025 875);
PAINT GREEN (-3025 875);
DISPLAY INVISIBLE (-3025 875);
FORCEPROP 2 LAST SEC 1
J 0
(-2800 925);
DISPLAY 0.680851 (-2800 925);
PAINT MONO (-2800 925);
DISPLAY INVISIBLE (-2800 925);
FORCEPROP 2 LAST SEC_TYPE RCL_GP
J 0
(-2800 925);
DISPLAY 1.021277 (-2800 925);
PAINT ORANGE (-2800 925);
DISPLAY INVISIBLE (-2800 925);
FORCEPROP 1 LAST PART_NUMBER 64.12005.6DL
R 1
J 0
(-3025 875);
DISPLAY 0.617021 (-3025 875);
PAINT GREEN (-3025 875);
DISPLAY INVISIBLE (-3025 875);
FORCEPROP 2 LAST CDS_LIB w_hdl
R 1
J 0
(-3025 875);
DISPLAY INVISIBLE (-3025 875);
FORCEPROP 1 LAST CDS_LMAN_SYM_OUTLINE -50,75,50,-75
R 1
J 0
(-3025 875);
DISPLAY 0.468085 (-3025 875);
PAINT GREEN (-3025 875);
DISPLAY INVISIBLE (-3025 875);
FORCEADD 120R2F-GP..1
R 1
(-3025 825);
FORCEPROP 2 LAST ATTRIBUTE 120OHM
J 0
(-2575 825);
DISPLAY 0.638298 (-2575 825);
PAINT GREEN (-2575 825);
FORCEPROP 1 LAST LOCATION R25W18
J 0
(-3350 825);
DISPLAY 0.617021 (-3350 825);
PAINT GREEN (-3350 825);
FORCEPROP 2 LASTPIN (-3150 825) $PN 1
J 2
(-3135 835);
DISPLAY 0.808511 (-3135 835);
PAINT ORANGE (-3135 835);
FORCEPROP 2 LAST RATED 1/16W
J 0
(-2300 825);
DISPLAY 0.638298 (-2300 825);
PAINT GREEN (-2300 825);
FORCEPROP 2 LAST TOLERANCE 1%
J 0
(-2400 825);
DISPLAY 0.638298 (-2400 825);
PAINT GREEN (-2400 825);
FORCEPROP 2 LASTPIN (-2900 825) $PN 2
J 0
(-2890 835);
DISPLAY 0.808511 (-2890 835);
PAINT ORANGE (-2890 835);
FORCEPROP 1 LAST VALUE 120R2F-GP
J 0
(-2800 825);
DISPLAY 0.617021 (-2800 825);
PAINT GREEN (-2800 825);
FORCEPROP 2 LAST PACK_SIZE 0402
J 0
(-2150 825);
DISPLAY 0.638298 (-2150 825);
PAINT GREEN (-2150 825);
FORCEPROP 1 LAST PATH I265
R 1
J 0
(-3025 825);
DISPLAY 0.617021 (-3025 825);
PAINT GREEN (-3025 825);
DISPLAY INVISIBLE (-3025 825);
FORCEPROP 1 LAST PACK_TYPE RCL_GP
R 1
J 0
(-3025 825);
DISPLAY 0.617021 (-3025 825);
PAINT GREEN (-3025 825);
DISPLAY INVISIBLE (-3025 825);
FORCEPROP 2 LAST SEC 1
J 0
(-2800 875);
DISPLAY 0.680851 (-2800 875);
PAINT MONO (-2800 875);
DISPLAY INVISIBLE (-2800 875);
FORCEPROP 2 LAST SEC_TYPE RCL_GP
J 0
(-2800 875);
DISPLAY 1.021277 (-2800 875);
PAINT ORANGE (-2800 875);
DISPLAY INVISIBLE (-2800 875);
FORCEPROP 1 LAST PART_NUMBER 64.12005.6DL
R 1
J 0
(-3025 825);
DISPLAY 0.617021 (-3025 825);
PAINT GREEN (-3025 825);
DISPLAY INVISIBLE (-3025 825);
FORCEPROP 2 LAST CDS_LIB w_hdl
R 1
J 0
(-3025 825);
DISPLAY INVISIBLE (-3025 825);
FORCEPROP 1 LAST CDS_LMAN_SYM_OUTLINE -50,75,50,-75
R 1
J 0
(-3025 825);
DISPLAY 0.468085 (-3025 825);
PAINT GREEN (-3025 825);
DISPLAY INVISIBLE (-3025 825);
FORCEADD 120R2F-GP..1
R 1
(-3025 725);
FORCEPROP 2 LAST ATTRIBUTE 120OHM
J 0
(-2575 725);
DISPLAY 0.638298 (-2575 725);
PAINT GREEN (-2575 725);
FORCEPROP 1 LAST VALUE 120R2F-GP
J 0
(-2800 725);
DISPLAY 0.617021 (-2800 725);
PAINT GREEN (-2800 725);
FORCEPROP 1 LAST LOCATION R25W20
J 0
(-3350 725);
DISPLAY 0.617021 (-3350 725);
PAINT GREEN (-3350 725);
FORCEPROP 2 LASTPIN (-3150 725) $PN 1
J 2
(-3135 735);
DISPLAY 0.808511 (-3135 735);
PAINT ORANGE (-3135 735);
FORCEPROP 2 LAST RATED 1/16W
J 0
(-2300 725);
DISPLAY 0.638298 (-2300 725);
PAINT GREEN (-2300 725);
FORCEPROP 2 LAST TOLERANCE 1%
J 0
(-2400 725);
DISPLAY 0.638298 (-2400 725);
PAINT GREEN (-2400 725);
FORCEPROP 2 LASTPIN (-2900 725) $PN 2
J 0
(-2890 735);
DISPLAY 0.808511 (-2890 735);
PAINT ORANGE (-2890 735);
FORCEPROP 2 LAST PACK_SIZE 0402
J 0
(-2150 725);
DISPLAY 0.638298 (-2150 725);
PAINT GREEN (-2150 725);
FORCEPROP 1 LAST PATH I266
R 1
J 0
(-3025 725);
DISPLAY 0.617021 (-3025 725);
PAINT GREEN (-3025 725);
DISPLAY INVISIBLE (-3025 725);
FORCEPROP 1 LAST PACK_TYPE RCL_GP
R 1
J 0
(-3025 725);
DISPLAY 0.617021 (-3025 725);
PAINT GREEN (-3025 725);
DISPLAY INVISIBLE (-3025 725);
FORCEPROP 2 LAST SEC 1
J 0
(-2800 775);
DISPLAY 0.680851 (-2800 775);
PAINT MONO (-2800 775);
DISPLAY INVISIBLE (-2800 775);
FORCEPROP 2 LAST SEC_TYPE RCL_GP
J 0
(-2800 775);
DISPLAY 1.021277 (-2800 775);
PAINT ORANGE (-2800 775);
DISPLAY INVISIBLE (-2800 775);
FORCEPROP 1 LAST PART_NUMBER 64.12005.6DL
R 1
J 0
(-3025 725);
DISPLAY 0.617021 (-3025 725);
PAINT GREEN (-3025 725);
DISPLAY INVISIBLE (-3025 725);
FORCEPROP 2 LAST CDS_LIB w_hdl
R 1
J 0
(-3025 725);
DISPLAY INVISIBLE (-3025 725);
FORCEPROP 1 LAST CDS_LMAN_SYM_OUTLINE -50,75,50,-75
R 1
J 0
(-3025 725);
DISPLAY 0.468085 (-3025 725);
PAINT GREEN (-3025 725);
DISPLAY INVISIBLE (-3025 725);
FORCEADD 120R2F-GP..1
R 1
(-3025 775);
FORCEPROP 2 LAST ATTRIBUTE 120OHM
J 0
(-2575 775);
DISPLAY 0.638298 (-2575 775);
PAINT GREEN (-2575 775);
FORCEPROP 1 LAST VALUE 120R2F-GP
J 0
(-2800 775);
DISPLAY 0.617021 (-2800 775);
PAINT GREEN (-2800 775);
FORCEPROP 1 LAST LOCATION R25W19
J 0
(-3350 775);
DISPLAY 0.617021 (-3350 775);
PAINT GREEN (-3350 775);
FORCEPROP 2 LASTPIN (-3150 775) $PN 1
J 2
(-3135 785);
DISPLAY 0.808511 (-3135 785);
PAINT ORANGE (-3135 785);
FORCEPROP 2 LAST RATED 1/16W
J 0
(-2300 775);
DISPLAY 0.638298 (-2300 775);
PAINT GREEN (-2300 775);
FORCEPROP 2 LAST TOLERANCE 1%
J 0
(-2400 775);
DISPLAY 0.638298 (-2400 775);
PAINT GREEN (-2400 775);
FORCEPROP 2 LASTPIN (-2900 775) $PN 2
J 0
(-2890 785);
DISPLAY 0.808511 (-2890 785);
PAINT ORANGE (-2890 785);
FORCEPROP 2 LAST PACK_SIZE 0402
J 0
(-2150 775);
DISPLAY 0.638298 (-2150 775);
PAINT GREEN (-2150 775);
FORCEPROP 1 LAST PATH I267
R 1
J 0
(-3025 775);
DISPLAY 0.617021 (-3025 775);
PAINT GREEN (-3025 775);
DISPLAY INVISIBLE (-3025 775);
FORCEPROP 1 LAST PACK_TYPE RCL_GP
R 1
J 0
(-3025 775);
DISPLAY 0.617021 (-3025 775);
PAINT GREEN (-3025 775);
DISPLAY INVISIBLE (-3025 775);
FORCEPROP 2 LAST SEC 1
J 0
(-2800 825);
DISPLAY 0.680851 (-2800 825);
PAINT MONO (-2800 825);
DISPLAY INVISIBLE (-2800 825);
FORCEPROP 2 LAST SEC_TYPE RCL_GP
J 0
(-2800 825);
DISPLAY 1.021277 (-2800 825);
PAINT ORANGE (-2800 825);
DISPLAY INVISIBLE (-2800 825);
FORCEPROP 1 LAST PART_NUMBER 64.12005.6DL
R 1
J 0
(-3025 775);
DISPLAY 0.617021 (-3025 775);
PAINT GREEN (-3025 775);
DISPLAY INVISIBLE (-3025 775);
FORCEPROP 2 LAST CDS_LIB w_hdl
R 1
J 0
(-3025 775);
DISPLAY INVISIBLE (-3025 775);
FORCEPROP 1 LAST CDS_LMAN_SYM_OUTLINE -50,75,50,-75
R 1
J 0
(-3025 775);
DISPLAY 0.468085 (-3025 775);
PAINT GREEN (-3025 775);
DISPLAY INVISIBLE (-3025 775);
FORCEADD 120R2F-GP..1
R 1
(-3025 525);
FORCEPROP 2 LAST ATTRIBUTE 120OHM
J 0
(-2575 525);
DISPLAY 0.638298 (-2575 525);
PAINT GREEN (-2575 525);
FORCEPROP 1 LAST VALUE 120R2F-GP
J 0
(-2800 525);
DISPLAY 0.617021 (-2800 525);
PAINT GREEN (-2800 525);
FORCEPROP 1 LAST LOCATION R25W24
J 0
(-3350 525);
DISPLAY 0.617021 (-3350 525);
PAINT GREEN (-3350 525);
FORCEPROP 2 LASTPIN (-3150 525) $PN 1
J 2
(-3135 535);
DISPLAY 0.808511 (-3135 535);
PAINT ORANGE (-3135 535);
FORCEPROP 2 LAST TOLERANCE 1%
J 0
(-2400 525);
DISPLAY 0.638298 (-2400 525);
PAINT GREEN (-2400 525);
FORCEPROP 2 LASTPIN (-2900 525) $PN 2
J 0
(-2890 535);
DISPLAY 0.808511 (-2890 535);
PAINT ORANGE (-2890 535);
FORCEPROP 2 LAST RATED 1/16W
J 0
(-2300 525);
DISPLAY 0.638298 (-2300 525);
PAINT GREEN (-2300 525);
FORCEPROP 2 LAST PACK_SIZE 0402
J 0
(-2150 525);
DISPLAY 0.638298 (-2150 525);
PAINT GREEN (-2150 525);
FORCEPROP 1 LAST PATH I268
R 1
J 0
(-3025 525);
DISPLAY 0.617021 (-3025 525);
PAINT GREEN (-3025 525);
DISPLAY INVISIBLE (-3025 525);
FORCEPROP 1 LAST PACK_TYPE RCL_GP
R 1
J 0
(-3025 525);
DISPLAY 0.617021 (-3025 525);
PAINT GREEN (-3025 525);
DISPLAY INVISIBLE (-3025 525);
FORCEPROP 2 LAST SEC 1
J 0
(-2800 575);
DISPLAY 0.680851 (-2800 575);
PAINT MONO (-2800 575);
DISPLAY INVISIBLE (-2800 575);
FORCEPROP 2 LAST SEC_TYPE RCL_GP
J 0
(-2800 575);
DISPLAY 1.021277 (-2800 575);
PAINT ORANGE (-2800 575);
DISPLAY INVISIBLE (-2800 575);
FORCEPROP 1 LAST PART_NUMBER 64.12005.6DL
R 1
J 0
(-3025 525);
DISPLAY 0.617021 (-3025 525);
PAINT GREEN (-3025 525);
DISPLAY INVISIBLE (-3025 525);
FORCEPROP 2 LAST CDS_LIB w_hdl
R 1
J 0
(-3025 525);
DISPLAY INVISIBLE (-3025 525);
FORCEPROP 1 LAST CDS_LMAN_SYM_OUTLINE -50,75,50,-75
R 1
J 0
(-3025 525);
DISPLAY 0.468085 (-3025 525);
PAINT GREEN (-3025 525);
DISPLAY INVISIBLE (-3025 525);
FORCEADD 120R2F-GP..1
R 1
(-3025 575);
FORCEPROP 2 LAST ATTRIBUTE 120OHM
J 0
(-2575 575);
DISPLAY 0.638298 (-2575 575);
PAINT GREEN (-2575 575);
FORCEPROP 1 LAST VALUE 120R2F-GP
J 0
(-2800 575);
DISPLAY 0.617021 (-2800 575);
PAINT GREEN (-2800 575);
FORCEPROP 2 LASTPIN (-2900 575) $PN 2
J 0
(-2890 585);
DISPLAY 0.808511 (-2890 585);
PAINT ORANGE (-2890 585);
FORCEPROP 1 LAST LOCATION R25W23
J 0
(-3350 575);
DISPLAY 0.617021 (-3350 575);
PAINT GREEN (-3350 575);
FORCEPROP 2 LASTPIN (-3150 575) $PN 1
J 2
(-3135 585);
DISPLAY 0.808511 (-3135 585);
PAINT ORANGE (-3135 585);
FORCEPROP 2 LAST RATED 1/16W
J 0
(-2300 575);
DISPLAY 0.638298 (-2300 575);
PAINT GREEN (-2300 575);
FORCEPROP 2 LAST TOLERANCE 1%
J 0
(-2400 575);
DISPLAY 0.638298 (-2400 575);
PAINT GREEN (-2400 575);
FORCEPROP 2 LAST PACK_SIZE 0402
J 0
(-2150 575);
DISPLAY 0.638298 (-2150 575);
PAINT GREEN (-2150 575);
FORCEPROP 1 LAST PATH I269
R 1
J 0
(-3025 575);
DISPLAY 0.617021 (-3025 575);
PAINT GREEN (-3025 575);
DISPLAY INVISIBLE (-3025 575);
FORCEPROP 1 LAST PACK_TYPE RCL_GP
R 1
J 0
(-3025 575);
DISPLAY 0.617021 (-3025 575);
PAINT GREEN (-3025 575);
DISPLAY INVISIBLE (-3025 575);
FORCEPROP 2 LAST SEC 1
J 0
(-2800 625);
DISPLAY 0.680851 (-2800 625);
PAINT MONO (-2800 625);
DISPLAY INVISIBLE (-2800 625);
FORCEPROP 2 LAST SEC_TYPE RCL_GP
J 0
(-2800 625);
DISPLAY 1.021277 (-2800 625);
PAINT ORANGE (-2800 625);
DISPLAY INVISIBLE (-2800 625);
FORCEPROP 1 LAST PART_NUMBER 64.12005.6DL
R 1
J 0
(-3025 575);
DISPLAY 0.617021 (-3025 575);
PAINT GREEN (-3025 575);
DISPLAY INVISIBLE (-3025 575);
FORCEPROP 2 LAST CDS_LIB w_hdl
R 1
J 0
(-3025 575);
DISPLAY INVISIBLE (-3025 575);
FORCEPROP 1 LAST CDS_LMAN_SYM_OUTLINE -50,75,50,-75
R 1
J 0
(-3025 575);
DISPLAY 0.468085 (-3025 575);
PAINT GREEN (-3025 575);
DISPLAY INVISIBLE (-3025 575);
FORCEADD 120R2F-GP..1
R 1
(-3025 625);
FORCEPROP 2 LAST ATTRIBUTE 120OHM
J 0
(-2575 625);
DISPLAY 0.638298 (-2575 625);
PAINT GREEN (-2575 625);
FORCEPROP 1 LAST VALUE 120R2F-GP
J 0
(-2800 625);
DISPLAY 0.617021 (-2800 625);
PAINT GREEN (-2800 625);
FORCEPROP 1 LAST LOCATION R25W22
J 0
(-3350 625);
DISPLAY 0.617021 (-3350 625);
PAINT GREEN (-3350 625);
FORCEPROP 2 LASTPIN (-3150 625) $PN 1
J 2
(-3135 635);
DISPLAY 0.808511 (-3135 635);
PAINT ORANGE (-3135 635);
FORCEPROP 2 LAST RATED 1/16W
J 0
(-2300 625);
DISPLAY 0.638298 (-2300 625);
PAINT GREEN (-2300 625);
FORCEPROP 2 LAST TOLERANCE 1%
J 0
(-2400 625);
DISPLAY 0.638298 (-2400 625);
PAINT GREEN (-2400 625);
FORCEPROP 2 LASTPIN (-2900 625) $PN 2
J 0
(-2890 635);
DISPLAY 0.808511 (-2890 635);
PAINT ORANGE (-2890 635);
FORCEPROP 2 LAST PACK_SIZE 0402
J 0
(-2150 625);
DISPLAY 0.638298 (-2150 625);
PAINT GREEN (-2150 625);
FORCEPROP 1 LAST PATH I270
R 1
J 0
(-3025 625);
DISPLAY 0.617021 (-3025 625);
PAINT GREEN (-3025 625);
DISPLAY INVISIBLE (-3025 625);
FORCEPROP 1 LAST PACK_TYPE RCL_GP
R 1
J 0
(-3025 625);
DISPLAY 0.617021 (-3025 625);
PAINT GREEN (-3025 625);
DISPLAY INVISIBLE (-3025 625);
FORCEPROP 2 LAST SEC 1
J 0
(-2800 675);
DISPLAY 0.680851 (-2800 675);
PAINT MONO (-2800 675);
DISPLAY INVISIBLE (-2800 675);
FORCEPROP 2 LAST SEC_TYPE RCL_GP
J 0
(-2800 675);
DISPLAY 1.021277 (-2800 675);
PAINT ORANGE (-2800 675);
DISPLAY INVISIBLE (-2800 675);
FORCEPROP 1 LAST PART_NUMBER 64.12005.6DL
R 1
J 0
(-3025 625);
DISPLAY 0.617021 (-3025 625);
PAINT GREEN (-3025 625);
DISPLAY INVISIBLE (-3025 625);
FORCEPROP 2 LAST CDS_LIB w_hdl
R 1
J 0
(-3025 625);
DISPLAY INVISIBLE (-3025 625);
FORCEPROP 1 LAST CDS_LMAN_SYM_OUTLINE -50,75,50,-75
R 1
J 0
(-3025 625);
DISPLAY 0.468085 (-3025 625);
PAINT GREEN (-3025 625);
DISPLAY INVISIBLE (-3025 625);
FORCEADD 120R2F-GP..1
R 1
(-3025 675);
FORCEPROP 2 LAST ATTRIBUTE 120OHM
J 0
(-2575 675);
DISPLAY 0.638298 (-2575 675);
PAINT GREEN (-2575 675);
FORCEPROP 1 LAST VALUE 120R2F-GP
J 0
(-2800 675);
DISPLAY 0.617021 (-2800 675);
PAINT GREEN (-2800 675);
FORCEPROP 1 LAST LOCATION R25W21
J 0
(-3350 675);
DISPLAY 0.617021 (-3350 675);
PAINT GREEN (-3350 675);
FORCEPROP 2 LASTPIN (-3150 675) $PN 1
J 2
(-3135 685);
DISPLAY 0.808511 (-3135 685);
PAINT ORANGE (-3135 685);
FORCEPROP 2 LAST RATED 1/16W
J 0
(-2300 675);
DISPLAY 0.638298 (-2300 675);
PAINT GREEN (-2300 675);
FORCEPROP 2 LAST TOLERANCE 1%
J 0
(-2400 675);
DISPLAY 0.638298 (-2400 675);
PAINT GREEN (-2400 675);
FORCEPROP 2 LASTPIN (-2900 675) $PN 2
J 0
(-2890 685);
DISPLAY 0.808511 (-2890 685);
PAINT ORANGE (-2890 685);
FORCEPROP 2 LAST PACK_SIZE 0402
J 0
(-2150 675);
DISPLAY 0.638298 (-2150 675);
PAINT GREEN (-2150 675);
FORCEPROP 1 LAST PATH I271
R 1
J 0
(-3025 675);
DISPLAY 0.617021 (-3025 675);
PAINT GREEN (-3025 675);
DISPLAY INVISIBLE (-3025 675);
FORCEPROP 1 LAST PACK_TYPE RCL_GP
R 1
J 0
(-3025 675);
DISPLAY 0.617021 (-3025 675);
PAINT GREEN (-3025 675);
DISPLAY INVISIBLE (-3025 675);
FORCEPROP 2 LAST SEC 1
J 0
(-2800 725);
DISPLAY 0.680851 (-2800 725);
PAINT MONO (-2800 725);
DISPLAY INVISIBLE (-2800 725);
FORCEPROP 2 LAST SEC_TYPE RCL_GP
J 0
(-2800 725);
DISPLAY 1.021277 (-2800 725);
PAINT ORANGE (-2800 725);
DISPLAY INVISIBLE (-2800 725);
FORCEPROP 1 LAST PART_NUMBER 64.12005.6DL
R 1
J 0
(-3025 675);
DISPLAY 0.617021 (-3025 675);
PAINT GREEN (-3025 675);
DISPLAY INVISIBLE (-3025 675);
FORCEPROP 2 LAST CDS_LIB w_hdl
R 1
J 0
(-3025 675);
DISPLAY INVISIBLE (-3025 675);
FORCEPROP 1 LAST CDS_LMAN_SYM_OUTLINE -50,75,50,-75
R 1
J 0
(-3025 675);
DISPLAY 0.468085 (-3025 675);
PAINT GREEN (-3025 675);
DISPLAY INVISIBLE (-3025 675);
FORCEADD 120R2F-GP..1
R 1
(-3025 425);
FORCEPROP 2 LAST ATTRIBUTE 120OHM
J 0
(-2575 425);
DISPLAY 0.638298 (-2575 425);
PAINT GREEN (-2575 425);
FORCEPROP 1 LAST LOCATION R25W26
J 0
(-3350 425);
DISPLAY 0.617021 (-3350 425);
PAINT GREEN (-3350 425);
FORCEPROP 2 LASTPIN (-3150 425) $PN 1
J 2
(-3135 435);
DISPLAY 0.808511 (-3135 435);
PAINT ORANGE (-3135 435);
FORCEPROP 2 LAST RATED 1/16W
J 0
(-2300 425);
DISPLAY 0.638298 (-2300 425);
PAINT GREEN (-2300 425);
FORCEPROP 2 LAST TOLERANCE 1%
J 0
(-2400 425);
DISPLAY 0.638298 (-2400 425);
PAINT GREEN (-2400 425);
FORCEPROP 2 LASTPIN (-2900 425) $PN 2
J 0
(-2890 435);
DISPLAY 0.808511 (-2890 435);
PAINT ORANGE (-2890 435);
FORCEPROP 1 LAST VALUE 120R2F-GP
J 0
(-2800 425);
DISPLAY 0.617021 (-2800 425);
PAINT GREEN (-2800 425);
FORCEPROP 2 LAST PACK_SIZE 0402
J 0
(-2150 425);
DISPLAY 0.638298 (-2150 425);
PAINT GREEN (-2150 425);
FORCEPROP 1 LAST PATH I274
R 1
J 0
(-3025 425);
DISPLAY 0.617021 (-3025 425);
PAINT GREEN (-3025 425);
DISPLAY INVISIBLE (-3025 425);
FORCEPROP 1 LAST PACK_TYPE RCL_GP
R 1
J 0
(-3025 425);
DISPLAY 0.617021 (-3025 425);
PAINT GREEN (-3025 425);
DISPLAY INVISIBLE (-3025 425);
FORCEPROP 2 LAST SEC 1
J 0
(-2800 475);
DISPLAY 0.680851 (-2800 475);
PAINT MONO (-2800 475);
DISPLAY INVISIBLE (-2800 475);
FORCEPROP 2 LAST SEC_TYPE RCL_GP
J 0
(-2800 475);
DISPLAY 1.021277 (-2800 475);
PAINT ORANGE (-2800 475);
DISPLAY INVISIBLE (-2800 475);
FORCEPROP 1 LAST PART_NUMBER 64.12005.6DL
R 1
J 0
(-3025 425);
DISPLAY 0.617021 (-3025 425);
PAINT GREEN (-3025 425);
DISPLAY INVISIBLE (-3025 425);
FORCEPROP 2 LAST CDS_LIB w_hdl
R 1
J 0
(-3025 425);
DISPLAY INVISIBLE (-3025 425);
FORCEPROP 1 LAST CDS_LMAN_SYM_OUTLINE -50,75,50,-75
R 1
J 0
(-3025 425);
DISPLAY 0.468085 (-3025 425);
PAINT GREEN (-3025 425);
DISPLAY INVISIBLE (-3025 425);
FORCEADD 120R2F-GP..1
R 1
(-3025 475);
FORCEPROP 2 LAST ATTRIBUTE 120OHM
J 0
(-2575 475);
DISPLAY 0.638298 (-2575 475);
PAINT GREEN (-2575 475);
FORCEPROP 1 LAST VALUE 120R2F-GP
J 0
(-2800 475);
DISPLAY 0.617021 (-2800 475);
PAINT GREEN (-2800 475);
FORCEPROP 1 LAST LOCATION R25W25
J 0
(-3350 475);
DISPLAY 0.617021 (-3350 475);
PAINT GREEN (-3350 475);
FORCEPROP 2 LASTPIN (-3150 475) $PN 1
J 2
(-3135 485);
DISPLAY 0.808511 (-3135 485);
PAINT ORANGE (-3135 485);
FORCEPROP 2 LAST TOLERANCE 1%
J 0
(-2400 475);
DISPLAY 0.638298 (-2400 475);
PAINT GREEN (-2400 475);
FORCEPROP 2 LASTPIN (-2900 475) $PN 2
J 0
(-2890 485);
DISPLAY 0.808511 (-2890 485);
PAINT ORANGE (-2890 485);
FORCEPROP 2 LAST RATED 1/16W
J 0
(-2300 475);
DISPLAY 0.638298 (-2300 475);
PAINT GREEN (-2300 475);
FORCEPROP 2 LAST PACK_SIZE 0402
J 0
(-2150 475);
DISPLAY 0.638298 (-2150 475);
PAINT GREEN (-2150 475);
FORCEPROP 1 LAST PATH I275
R 1
J 0
(-3025 475);
DISPLAY 0.617021 (-3025 475);
PAINT GREEN (-3025 475);
DISPLAY INVISIBLE (-3025 475);
FORCEPROP 1 LAST PACK_TYPE RCL_GP
R 1
J 0
(-3025 475);
DISPLAY 0.617021 (-3025 475);
PAINT GREEN (-3025 475);
DISPLAY INVISIBLE (-3025 475);
FORCEPROP 2 LAST SEC 1
J 0
(-2800 525);
DISPLAY 0.680851 (-2800 525);
PAINT MONO (-2800 525);
DISPLAY INVISIBLE (-2800 525);
FORCEPROP 2 LAST SEC_TYPE RCL_GP
J 0
(-2800 525);
DISPLAY 1.021277 (-2800 525);
PAINT ORANGE (-2800 525);
DISPLAY INVISIBLE (-2800 525);
FORCEPROP 1 LAST PART_NUMBER 64.12005.6DL
R 1
J 0
(-3025 475);
DISPLAY 0.617021 (-3025 475);
PAINT GREEN (-3025 475);
DISPLAY INVISIBLE (-3025 475);
FORCEPROP 2 LAST CDS_LIB w_hdl
R 1
J 0
(-3025 475);
DISPLAY INVISIBLE (-3025 475);
FORCEPROP 1 LAST CDS_LMAN_SYM_OUTLINE -50,75,50,-75
R 1
J 0
(-3025 475);
DISPLAY 0.468085 (-3025 475);
PAINT GREEN (-3025 475);
DISPLAY INVISIBLE (-3025 475);
FORCEADD RES..1
(1250 -1550);
FORCEPROP 1 LAST PART_NUMBER G21796-047
J 0
(1300 -1650);
DISPLAY 0.617021 (1300 -1650);
PAINT BLUE (1300 -1650);
FORCEPROP 1 LAST TOLERANCE 1%
J 0
(1300 -1600);
DISPLAY 0.617021 (1300 -1600);
PAINT SKYBLUE (1300 -1600);
FORCEPROP 1 LAST WATTAGE 1/16W
J 2
(1500 -1600);
DISPLAY 0.617021 (1500 -1600);
PAINT SKYBLUE (1500 -1600);
FORCEPROP 1 LAST VALUE 49.9
J 2
(1275 -1600);
DISPLAY 0.617021 (1275 -1600);
PAINT SKYBLUE (1275 -1600);
FORCEPROP 1 LAST PACK_TYPE 0402
J 0
(1175 -1650);
DISPLAY 0.617021 (1175 -1650);
PAINT SKYBLUE (1175 -1650);
FORCEPROP 1 LAST MATERIAL CHIP
J 0
(1050 -1650);
DISPLAY 0.617021 (1050 -1650);
PAINT SKYBLUE (1050 -1650);
FORCEPROP 1 LAST LOCATION R1T40
J 0
(1050 -1600);
DISPLAY 0.617021 (1050 -1600);
PAINT AQUA (1050 -1600);
FORCEPROP 1 LASTPIN (1350 -1550) $PN 2
J 0
(1312 -1538);
DISPLAY 0.617021 (1312 -1538);
PAINT ORANGE (1312 -1538);
FORCEPROP 1 LASTPIN (1150 -1550) $PN 1
J 0
(1162 -1538);
DISPLAY 0.617021 (1162 -1538);
PAINT ORANGE (1162 -1538);
FORCEPROP 2 LAST CDS_LOCATION R1T40
J 0
(1250 -1450);
DISPLAY 0.617021 (1250 -1450);
PAINT AQUA (1250 -1450);
DISPLAY INVISIBLE (1250 -1450);
FORCEPROP 1 LAST PATH I278
J 0
(1200 -1400);
DISPLAY 0.978723 (1200 -1400);
PAINT WHITE (1200 -1400);
DISPLAY INVISIBLE (1200 -1400);
FORCEPROP 0 LAST ROOM CPU0
J 0
(1200 -1350);
DISPLAY 1.021277 (1200 -1350);
PAINT ORANGE (1200 -1350);
DISPLAY INVISIBLE (1200 -1350);
FORCEPROP 2 LAST SEC 1
J 0
(1200 -1350);
DISPLAY 0.680851 (1200 -1350);
PAINT MONO (1200 -1350);
DISPLAY INVISIBLE (1200 -1350);
FORCEPROP 0 LAST BOM_COST PROC_SOCKET
J 0
(1250 -1350);
DISPLAY 1.021277 (1250 -1350);
PAINT ORANGE (1250 -1350);
DISPLAY INVISIBLE (1250 -1350);
FORCEPROP 2 LAST SEC_TYPE 0402
J 0
(1200 -1350);
DISPLAY 1.021277 (1200 -1350);
PAINT ORANGE (1200 -1350);
DISPLAY INVISIBLE (1200 -1350);
FORCEPROP 2 LAST CDS_LIB mstr_discrete
J 0
(1250 -1550);
PAINT ORANGE (1250 -1550);
DISPLAY INVISIBLE (1250 -1550);
FORCEADD RES..1
(1250 -1950);
FORCEPROP 1 LAST VALUE 49.9
J 2
(1275 -2000);
DISPLAY 0.617021 (1275 -2000);
PAINT SKYBLUE (1275 -2000);
FORCEPROP 1 LAST WATTAGE 1/16W
J 2
(1500 -2000);
DISPLAY 0.617021 (1500 -2000);
PAINT SKYBLUE (1500 -2000);
FORCEPROP 1 LAST LOCATION R1T28
J 0
(1050 -2000);
DISPLAY 0.617021 (1050 -2000);
PAINT AQUA (1050 -2000);
FORCEPROP 1 LAST MATERIAL CHIP
J 0
(1050 -2050);
DISPLAY 0.617021 (1050 -2050);
PAINT SKYBLUE (1050 -2050);
FORCEPROP 1 LAST PACK_TYPE 0402
J 0
(1175 -2050);
DISPLAY 0.617021 (1175 -2050);
PAINT SKYBLUE (1175 -2050);
FORCEPROP 1 LAST TOLERANCE 1%
J 0
(1300 -2000);
DISPLAY 0.617021 (1300 -2000);
PAINT SKYBLUE (1300 -2000);
FORCEPROP 1 LAST PART_NUMBER G21796-047
J 0
(1300 -2050);
DISPLAY 0.617021 (1300 -2050);
PAINT BLUE (1300 -2050);
FORCEPROP 1 LASTPIN (1350 -1950) $PN 2
J 0
(1312 -1938);
DISPLAY 0.617021 (1312 -1938);
PAINT ORANGE (1312 -1938);
FORCEPROP 1 LASTPIN (1150 -1950) $PN 1
J 0
(1162 -1938);
DISPLAY 0.617021 (1162 -1938);
PAINT ORANGE (1162 -1938);
FORCEPROP 2 LAST CDS_LOCATION R1T28
J 0
(1250 -1850);
DISPLAY 0.617021 (1250 -1850);
PAINT AQUA (1250 -1850);
DISPLAY INVISIBLE (1250 -1850);
FORCEPROP 1 LAST PATH I279
J 0
(1200 -1800);
DISPLAY 0.978723 (1200 -1800);
PAINT WHITE (1200 -1800);
DISPLAY INVISIBLE (1200 -1800);
FORCEPROP 0 LAST ROOM CPU0
J 0
(1200 -1750);
DISPLAY 1.021277 (1200 -1750);
PAINT ORANGE (1200 -1750);
DISPLAY INVISIBLE (1200 -1750);
FORCEPROP 2 LAST SEC 1
J 0
(1200 -1750);
DISPLAY 0.680851 (1200 -1750);
PAINT MONO (1200 -1750);
DISPLAY INVISIBLE (1200 -1750);
FORCEPROP 0 LAST BOM_COST PROC_SOCKET
J 0
(1250 -1750);
DISPLAY 1.021277 (1250 -1750);
PAINT ORANGE (1250 -1750);
DISPLAY INVISIBLE (1250 -1750);
FORCEPROP 2 LAST SEC_TYPE 0402
J 0
(1200 -1750);
DISPLAY 1.021277 (1200 -1750);
PAINT ORANGE (1200 -1750);
DISPLAY INVISIBLE (1200 -1750);
FORCEPROP 2 LAST CDS_LIB mstr_discrete
J 0
(1250 -1950);
PAINT ORANGE (1250 -1950);
DISPLAY INVISIBLE (1250 -1950);
FORCEADD H5AN4G6NAFR-TFC-GP..1
(2650 25);
FORCEPROP 0 LASTPIN (3125 -200) $PN T3
J 0
(3135 -190);
DISPLAY 0.808511 (3135 -190);
PAINT MONO (3135 -190);
FORCEPROP 1 LAST VALUE H5AN4G6NAFR-TFC-GP
J 0
(2325 -1550);
DISPLAY 0.617021 (2325 -1550);
PAINT GREEN (2325 -1550);
FORCEPROP 0 LASTPIN (3125 -1400) $PN T1
J 0
(3135 -1390);
DISPLAY 0.808511 (3135 -1390);
PAINT MONO (3135 -1390);
FORCEPROP 0 LASTPIN (2175 -1200) $PN E7
J 2
(2165 -1190);
DISPLAY 0.808511 (2165 -1190);
PAINT MONO (2165 -1190);
FORCEPROP 0 LASTPIN (2175 -1150) $PN E2
J 2
(2165 -1140);
DISPLAY 0.808511 (2165 -1140);
PAINT MONO (2165 -1140);
FORCEPROP 0 LASTPIN (2175 -1350) $PN N2
J 2
(2165 -1340);
DISPLAY 0.808511 (2165 -1340);
PAINT MONO (2165 -1340);
FORCEPROP 0 LASTPIN (3125 -900) $PN H9
J 0
(3135 -890);
DISPLAY 0.808511 (3135 -890);
PAINT MONO (3135 -890);
FORCEPROP 0 LASTPIN (3125 -1050) $PN E1
J 0
(3135 -1040);
DISPLAY 0.808511 (3135 -1040);
PAINT MONO (3135 -1040);
FORCEPROP 0 LASTPIN (3125 -450) $PN A2
J 0
(3135 -440);
DISPLAY 0.808511 (3135 -440);
PAINT MONO (3135 -440);
FORCEPROP 0 LASTPIN (3125 -500) $PN A8
J 0
(3135 -490);
DISPLAY 0.808511 (3135 -490);
PAINT MONO (3135 -490);
FORCEPROP 0 LASTPIN (2175 -50) $PN B8
J 2
(2165 -40);
DISPLAY 0.808511 (2165 -40);
PAINT MONO (2165 -40);
FORCEPROP 0 LASTPIN (2175 0) $PN A3
J 2
(2165 10);
DISPLAY 0.808511 (2165 10);
PAINT MONO (2165 10);
FORCEPROP 0 LASTPIN (2175 -1400) $PN N8
J 2
(2165 -1390);
DISPLAY 0.808511 (2165 -1390);
PAINT MONO (2165 -1390);
FORCEPROP 0 LASTPIN (3125 1250) $PN N3
J 0
(3135 1260);
DISPLAY 0.808511 (3135 1260);
PAINT MONO (3135 1260);
FORCEPROP 0 LASTPIN (3125 -300) $PN T7
J 0
(3135 -290);
DISPLAY 0.808511 (3135 -290);
PAINT MONO (3135 -290);
FORCEPROP 0 LASTPIN (2175 350) $PN B1
J 2
(2165 360);
DISPLAY 0.808511 (2165 360);
PAINT MONO (2165 360);
FORCEPROP 0 LASTPIN (2175 1150) $PN L1
J 2
(2165 1160);
DISPLAY 0.808511 (2165 1160);
PAINT MONO (2165 1160);
FORCEPROP 0 LASTPIN (3125 1200) $PN P8
J 0
(3135 1210);
DISPLAY 0.808511 (3135 1210);
PAINT MONO (3135 1210);
FORCEPROP 0 LASTPIN (3125 1050) $PN R2
J 0
(3135 1060);
DISPLAY 0.808511 (3135 1060);
PAINT MONO (3135 1060);
FORCEPROP 0 LASTPIN (2175 900) $PN A1
J 2
(2165 910);
DISPLAY 0.808511 (2165 910);
PAINT MONO (2165 910);
FORCEPROP 0 LASTPIN (3125 1000) $PN R7
J 0
(3135 1010);
DISPLAY 0.808511 (3135 1010);
PAINT MONO (3135 1010);
FORCEPROP 0 LASTPIN (2175 450) $PN J8
J 2
(2165 460);
DISPLAY 0.808511 (2165 460);
PAINT MONO (2165 460);
FORCEPROP 0 LASTPIN (2175 150) $PN M1
J 2
(2165 160);
DISPLAY 0.808511 (2165 160);
PAINT MONO (2165 160);
FORCEPROP 0 LASTPIN (2175 300) $PN R9
J 2
(2165 310);
DISPLAY 0.808511 (2165 310);
PAINT MONO (2165 310);
FORCEPROP 0 LASTPIN (2175 -550) $PN H3
J 2
(2165 -540);
DISPLAY 0.808511 (2165 -540);
PAINT MONO (2165 -540);
FORCEPROP 0 LASTPIN (3125 -700) $PN E3
J 0
(3135 -690);
DISPLAY 0.808511 (3135 -690);
PAINT MONO (3135 -690);
FORCEPROP 0 LASTPIN (2175 500) $PN J2
J 2
(2165 510);
DISPLAY 0.808511 (2165 510);
PAINT MONO (2165 510);
FORCEPROP 0 LASTPIN (2175 -150) $PN C7
J 2
(2165 -140);
DISPLAY 0.808511 (2165 -140);
PAINT MONO (2165 -140);
FORCEPROP 0 LASTPIN (2175 1300) $PN G7
J 2
(2165 1310);
DISPLAY 0.808511 (2165 1310);
PAINT MONO (2165 1310);
FORCEPROP 0 LASTPIN (3125 1300) $PN N7
J 0
(3135 1310);
DISPLAY 0.808511 (3135 1310);
PAINT MONO (3135 1310);
FORCEPROP 0 LASTPIN (2175 -750) $PN J3
J 2
(2165 -740);
DISPLAY 0.808511 (2165 -740);
PAINT MONO (2165 -740);
FORCEPROP 0 LASTPIN (2175 -700) $PN H8
J 2
(2165 -690);
DISPLAY 0.808511 (2165 -690);
PAINT MONO (2165 -690);
FORCEPROP 0 LASTPIN (2175 -650) $PN H2
J 2
(2165 -640);
DISPLAY 0.808511 (2165 -640);
PAINT MONO (2165 -640);
FORCEPROP 0 LASTPIN (3125 0) $PN M2
J 0
(3135 10);
DISPLAY 0.808511 (3135 10);
PAINT MONO (3135 10);
FORCEPROP 0 LASTPIN (3125 300) $PN L7
J 0
(3135 310);
DISPLAY 0.808511 (3135 310);
PAINT MONO (3135 310);
FORCEPROP 0 LASTPIN (2175 -200) $PN C2
J 2
(2165 -190);
DISPLAY 0.808511 (2165 -190);
PAINT MONO (2165 -190);
FORCEPROP 0 LASTPIN (3125 -850) $PN H1
J 0
(3135 -840);
DISPLAY 0.808511 (3135 -840);
PAINT MONO (3135 -840);
FORCEPROP 0 LASTPIN (3125 -800) $PN F1
J 0
(3135 -790);
DISPLAY 0.808511 (3135 -790);
PAINT MONO (3135 -790);
FORCEPROP 0 LASTPIN (2175 -1050) $PN G3
J 2
(2165 -1040);
DISPLAY 0.808511 (2165 -1040);
PAINT MONO (2165 -1040);
FORCEPROP 0 LASTPIN (2175 -450) $PN G2
J 2
(2165 -440);
DISPLAY 0.808511 (2165 -440);
PAINT MONO (2165 -440);
FORCEPROP 0 LASTPIN (2175 -100) $PN C3
J 2
(2165 -90);
DISPLAY 0.808511 (2165 -90);
PAINT MONO (2165 -90);
FORCEPROP 0 LASTPIN (3125 650) $PN L8
J 0
(3135 660);
DISPLAY 0.808511 (3135 660);
PAINT MONO (3135 660);
FORCEPROP 0 LASTPIN (3125 1150) $PN P2
J 0
(3135 1160);
DISPLAY 0.808511 (3135 1160);
PAINT MONO (3135 1160);
FORCEPROP 0 LASTPIN (3125 1100) $PN R8
J 0
(3135 1110);
DISPLAY 0.808511 (3135 1110);
PAINT MONO (3135 1110);
FORCEPROP 0 LASTPIN (3125 800) $PN T8
J 0
(3135 810);
DISPLAY 0.808511 (3135 810);
PAINT MONO (3135 810);
FORCEPROP 1 LAST LOCATION U25W5
J 0
(2325 1575);
DISPLAY 0.617021 (2325 1575);
PAINT GREEN (2325 1575);
FORCEPROP 0 LASTPIN (2175 1250) $PN J1
J 2
(2165 1260);
DISPLAY 0.808511 (2165 1260);
PAINT MONO (2165 1260);
FORCEPROP 0 LASTPIN (2175 1200) $PN J9
J 2
(2165 1210);
DISPLAY 0.808511 (2165 1210);
PAINT MONO (2165 1210);
FORCEPROP 0 LASTPIN (2175 1000) $PN T9
J 2
(2165 1010);
DISPLAY 0.808511 (2165 1010);
PAINT MONO (2165 1010);
FORCEPROP 0 LASTPIN (2175 800) $PN C1
J 2
(2165 810);
DISPLAY 0.808511 (2165 810);
PAINT MONO (2165 810);
FORCEPROP 0 LASTPIN (2175 700) $PN F2
J 2
(2165 710);
DISPLAY 0.808511 (2165 710);
PAINT MONO (2165 710);
FORCEPROP 0 LASTPIN (2175 600) $PN G1
J 2
(2165 610);
DISPLAY 0.808511 (2165 610);
PAINT MONO (2165 610);
FORCEPROP 0 LASTPIN (2175 550) $PN G9
J 2
(2165 560);
DISPLAY 0.808511 (2165 560);
PAINT MONO (2165 560);
FORCEPROP 0 LASTPIN (2175 -250) $PN C8
J 2
(2165 -240);
DISPLAY 0.808511 (2165 -240);
PAINT MONO (2165 -240);
FORCEPROP 0 LASTPIN (2175 -300) $PN D3
J 2
(2165 -290);
DISPLAY 0.808511 (2165 -290);
PAINT MONO (2165 -290);
FORCEPROP 0 LASTPIN (2175 -350) $PN D7
J 2
(2165 -340);
DISPLAY 0.808511 (2165 -340);
PAINT MONO (2165 -340);
FORCEPROP 0 LASTPIN (2175 -800) $PN J7
J 2
(2165 -790);
DISPLAY 0.808511 (2165 -790);
PAINT MONO (2165 -790);
FORCEPROP 0 LASTPIN (3125 1400) $PN P7
J 0
(3135 1410);
DISPLAY 0.808511 (3135 1410);
PAINT MONO (3135 1410);
FORCEPROP 0 LASTPIN (3125 700) $PN M8
J 0
(3135 710);
DISPLAY 0.808511 (3135 710);
PAINT MONO (3135 710);
FORCEPROP 0 LASTPIN (3125 100) $PN K3
J 0
(3135 110);
DISPLAY 0.808511 (3135 110);
PAINT MONO (3135 110);
FORCEPROP 0 LASTPIN (3125 -100) $PN N9
J 0
(3135 -90);
DISPLAY 0.808511 (3135 -90);
PAINT MONO (3135 -90);
FORCEPROP 0 LASTPIN (3125 500) $PN K7
J 0
(3135 510);
DISPLAY 0.808511 (3135 510);
PAINT MONO (3135 510);
FORCEPROP 0 LASTPIN (3125 450) $PN K8
J 0
(3135 460);
DISPLAY 0.808511 (3135 460);
PAINT MONO (3135 460);
FORCEPROP 0 LASTPIN (3125 350) $PN L3
J 0
(3135 360);
DISPLAY 0.808511 (3135 360);
PAINT MONO (3135 360);
FORCEPROP 0 LASTPIN (3125 250) $PN P1
J 0
(3135 260);
DISPLAY 0.808511 (3135 260);
PAINT MONO (3135 260);
FORCEPROP 0 LASTPIN (3125 200) $PN P9
J 0
(3135 210);
DISPLAY 0.808511 (3135 210);
PAINT MONO (3135 210);
FORCEPROP 0 LASTPIN (3125 -1000) $PN B2
J 0
(3135 -990);
DISPLAY 0.808511 (3135 -990);
PAINT MONO (3135 -990);
FORCEPROP 0 LASTPIN (3125 -1150) $PN G8
J 0
(3135 -1140);
DISPLAY 0.808511 (3135 -1140);
PAINT MONO (3135 -1140);
FORCEPROP 0 LASTPIN (3125 -1200) $PN K1
J 0
(3135 -1190);
DISPLAY 0.808511 (3135 -1190);
PAINT MONO (3135 -1190);
FORCEPROP 0 LASTPIN (3125 -1250) $PN K9
J 0
(3135 -1240);
DISPLAY 0.808511 (3135 -1240);
PAINT MONO (3135 -1240);
FORCEPROP 0 LASTPIN (3125 -1300) $PN M9
J 0
(3135 -1290);
DISPLAY 0.808511 (3135 -1290);
PAINT MONO (3135 -1290);
FORCEPROP 0 LASTPIN (3125 -1350) $PN N1
J 0
(3135 -1340);
DISPLAY 0.808511 (3135 -1340);
PAINT MONO (3135 -1340);
FORCEPROP 0 LASTPIN (3125 -550) $PN C9
J 0
(3135 -540);
DISPLAY 0.808511 (3135 -540);
PAINT MONO (3135 -540);
FORCEPROP 0 LASTPIN (3125 -650) $PN D8
J 0
(3135 -640);
DISPLAY 0.808511 (3135 -640);
PAINT MONO (3135 -640);
FORCEPROP 0 LASTPIN (3125 -750) $PN E8
J 0
(3135 -740);
DISPLAY 0.808511 (3135 -740);
PAINT MONO (3135 -740);
FORCEPROP 0 LASTPIN (2175 -950) $PN B7
J 2
(2165 -940);
DISPLAY 0.808511 (2165 -940);
PAINT MONO (2165 -940);
FORCEPROP 0 LASTPIN (2175 -1000) $PN F3
J 2
(2165 -990);
DISPLAY 0.808511 (2165 -990);
PAINT MONO (2165 -990);
FORCEPROP 0 LASTPIN (3125 -1100) $PN E9
J 0
(3135 -1090);
DISPLAY 0.808511 (3135 -1090);
PAINT MONO (3135 -1090);
FORCEPROP 0 LASTPIN (2175 1100) $PN L9
J 2
(2165 1110);
DISPLAY 0.808511 (2165 1110);
PAINT MONO (2165 1110);
FORCEPROP 0 LASTPIN (2175 1400) $PN B9
J 2
(2165 1410);
DISPLAY 0.808511 (2165 1410);
PAINT MONO (2165 1410);
FORCEPROP 0 LASTPIN (2175 -600) $PN H7
J 2
(2165 -590);
DISPLAY 0.808511 (2165 -590);
PAINT MONO (2165 -590);
FORCEPROP 0 LASTPIN (2175 -500) $PN F7
J 2
(2165 -490);
DISPLAY 0.808511 (2165 -490);
PAINT MONO (2165 -490);
FORCEPROP 0 LASTPIN (2175 1450) $PN B3
J 2
(2165 1460);
DISPLAY 0.808511 (2165 1460);
PAINT MONO (2165 1460);
FORCEPROP 0 LASTPIN (3125 950) $PN M3
J 0
(3135 960);
DISPLAY 0.808511 (3135 960);
PAINT MONO (3135 960);
FORCEPROP 0 LASTPIN (3125 750) $PN L2
J 0
(3135 760);
DISPLAY 0.808511 (3135 760);
PAINT MONO (3135 760);
FORCEPROP 0 LASTPIN (2175 650) $PN F8
J 2
(2165 660);
DISPLAY 0.808511 (2165 660);
PAINT MONO (2165 660);
FORCEPROP 0 LASTPIN (3125 550) $PN K2
J 0
(3135 560);
DISPLAY 0.808511 (3135 560);
PAINT MONO (3135 560);
FORCEPROP 0 LASTPIN (2175 -900) $PN A7
J 2
(2165 -890);
DISPLAY 0.808511 (2165 -890);
PAINT MONO (2165 -890);
FORCEPROP 0 LASTPIN (3125 1450) $PN P3
J 0
(3135 1460);
DISPLAY 0.808511 (3135 1460);
PAINT MONO (3135 1460);
FORCEPROP 0 LASTPIN (3125 1350) $PN R3
J 0
(3135 1360);
DISPLAY 0.808511 (3135 1360);
PAINT MONO (3135 1360);
FORCEPROP 0 LASTPIN (2175 1350) $PN D1
J 2
(2165 1360);
DISPLAY 0.808511 (2165 1360);
PAINT MONO (2165 1360);
FORCEPROP 0 LASTPIN (3125 -600) $PN D2
J 0
(3135 -590);
DISPLAY 0.808511 (3135 -590);
PAINT MONO (3135 -590);
FORCEPROP 0 LASTPIN (2175 1050) $PN R1
J 2
(2165 1060);
DISPLAY 0.808511 (2165 1060);
PAINT MONO (2165 1060);
FORCEPROP 0 LASTPIN (3125 900) $PN T2
J 0
(3135 910);
DISPLAY 0.808511 (3135 910);
PAINT MONO (3135 910);
FORCEPROP 0 LASTPIN (3125 850) $PN M7
J 0
(3135 860);
DISPLAY 0.808511 (3135 860);
PAINT MONO (3135 860);
FORCEPROP 0 LASTPIN (2175 100) $PN F9
J 2
(2165 110);
DISPLAY 0.808511 (2165 110);
PAINT MONO (2165 110);
FORCEPROP 0 LASTPIN (2175 850) $PN A9
J 2
(2165 860);
DISPLAY 0.808511 (2165 860);
PAINT MONO (2165 860);
FORCEPROP 0 LASTPIN (2175 750) $PN D9
J 2
(2165 760);
DISPLAY 0.808511 (2165 760);
PAINT MONO (2165 760);
FORCEPROP 1 LAST PACK_TYPE MEMORY-G2
J 0
(2650 25);
DISPLAY 0.617021 (2650 25);
PAINT GREEN (2650 25);
DISPLAY INVISIBLE (2650 25);
FORCEPROP 1 LAST PART_NUMBER 072.00546.0A0U
J 0
(2650 25);
DISPLAY 0.617021 (2650 25);
PAINT GREEN (2650 25);
DISPLAY INVISIBLE (2650 25);
FORCEPROP 2 LAST CDS_LIB w_hdl
J 0
(2650 25);
PAINT MONO (2650 25);
DISPLAY INVISIBLE (2650 25);
FORCEPROP 1 LAST CDS_LMAN_SYM_OUTLINE -325,1525,325,-1525
J 0
(2650 25);
DISPLAY 0.468085 (2650 25);
PAINT GREEN (2650 25);
DISPLAY INVISIBLE (2650 25);
FORCEPROP 0 LAST CDS_LOCATION U25W5
J 0
(2325 1625);
PAINT MONO (2325 1625);
DISPLAY INVISIBLE (2325 1625);
FORCEPROP 0 LAST $SEC 1
J 0
(2325 1625);
PAINT MONO (2325 1625);
DISPLAY INVISIBLE (2325 1625);
FORCEPROP 0 LAST CDS_SEC 1
J 0
(2325 1625);
PAINT MONO (2325 1625);
DISPLAY INVISIBLE (2325 1625);
FORCEPROP 1 LAST PATH I49
J 0
(2650 25);
DISPLAY 0.617021 (2650 25);
PAINT GREEN (2650 25);
DISPLAY INVISIBLE (2650 25);
FORCEADD OFFPAGE..3
(3800 -200);
FORCEPROP 2 LAST $XR0 151 
J 0
(4014 -200);
DISPLAY 0.638298 (4014 -200);
PAINT MONO (4014 -200);
FORCEPROP 1 LAST COMMENT_BODY TRUE
J 0
(3750 -300);
DISPLAY 0.872340 (3750 -300);
PAINT GREEN (3750 -300);
DISPLAY INVISIBLE (3750 -300);
FORCEPROP 1 LAST OFFPAGE TRUE
J 0
(4125 -325);
DISPLAY 0.872340 (4125 -325);
PAINT GREEN (4125 -325);
DISPLAY INVISIBLE (4125 -325);
FORCEPROP 2 LAST PATH I50
J 0
(4025 -150);
DISPLAY 1.021277 (4025 -150);
PAINT ORANGE (4025 -150);
DISPLAY INVISIBLE (4025 -150);
FORCEPROP 2 LAST CDS_LIB mstr_standard
J 0
(3800 -200);
PAINT MONO (3800 -200);
DISPLAY INVISIBLE (3800 -200);
FORCEADD W_VCC_CIRCLE..1
(50 1825);
FORCEPROP 3 LASTPIN (50 1825) SIG_NAME P1V2_AUX_BMC\g
J 0
(60 1835);
DISPLAY 0.659574 (60 1835);
PAINT MONO (60 1835);
DISPLAY INVISIBLE (60 1835);
FORCEPROP 1 LAST HDL_POWER P1V2_AUX_BMC
J 1
(71 1900);
DISPLAY 0.872340 (71 1900);
PAINT ORANGE (71 1900);
FORCEPROP 1 LAST BODY_TYPE PLUMBING
J 0
(62 1819);
DISPLAY 0.340426 (62 1819);
PAINT GREEN (62 1819);
DISPLAY INVISIBLE (62 1819);
FORCEPROP 1 LAST CDS_LMAN_SYM_OUTLINE -100,100,100,-100
J 0
(50 1825);
DISPLAY 0.468085 (50 1825);
PAINT GREEN (50 1825);
DISPLAY INVISIBLE (50 1825);
FORCEPROP 2 LAST CDS_LIB w_power
J 0
(50 1825);
PAINT MONO (50 1825);
DISPLAY INVISIBLE (50 1825);
FORCEPROP 1 LAST PATH I51
J 0
(50 1825);
DISPLAY 0.617021 (50 1825);
PAINT GREEN (50 1825);
DISPLAY INVISIBLE (50 1825);
FORCEADD OFFPAGE..2
(4150 1975);
FORCEPROP 2 LAST $XR1 151 
J 0
(4339 1939);
DISPLAY 0.638298 (4339 1939);
PAINT MONO (4339 1939);
FORCEPROP 2 LAST $XR0 146 
J 0
(4339 1975);
DISPLAY 0.638298 (4339 1975);
PAINT MONO (4339 1975);
FORCEPROP 1 LAST COMMENT_BODY TRUE
J 0
(4105 1880);
DISPLAY 0.872340 (4105 1880);
PAINT GREEN (4105 1880);
DISPLAY INVISIBLE (4105 1880);
FORCEPROP 1 LAST OFFPAGE TRUE
J 0
(4475 1850);
DISPLAY 0.872340 (4475 1850);
PAINT GREEN (4475 1850);
DISPLAY INVISIBLE (4475 1850);
FORCEPROP 2 LAST CDS_LIB mstr_standard
J 0
(4150 1975);
PAINT ORANGE (4150 1975);
DISPLAY INVISIBLE (4150 1975);
FORCEPROP 2 LAST PATH I52
J 0
(4350 2025);
DISPLAY 1.021277 (4350 2025);
PAINT ORANGE (4350 2025);
DISPLAY INVISIBLE (4350 2025);
FORCEADD W_VCC_CIRCLE..1
(2775 2300);
FORCEPROP 3 LASTPIN (2775 2300) SIG_NAME P1V2_AUX_BMC\g
J 0
(2785 2310);
DISPLAY 0.659574 (2785 2310);
PAINT MONO (2785 2310);
DISPLAY INVISIBLE (2785 2310);
FORCEPROP 1 LAST HDL_POWER P1V2_AUX_BMC
J 1
(2796 2375);
DISPLAY 0.872340 (2796 2375);
PAINT ORANGE (2796 2375);
FORCEPROP 1 LAST BODY_TYPE PLUMBING
J 0
(2787 2294);
DISPLAY 0.340426 (2787 2294);
PAINT GREEN (2787 2294);
DISPLAY INVISIBLE (2787 2294);
FORCEPROP 1 LAST CDS_LMAN_SYM_OUTLINE -100,100,100,-100
J 0
(2775 2300);
DISPLAY 0.468085 (2775 2300);
PAINT GREEN (2775 2300);
DISPLAY INVISIBLE (2775 2300);
FORCEPROP 2 LAST CDS_LIB w_power
J 0
(2775 2300);
PAINT MONO (2775 2300);
DISPLAY INVISIBLE (2775 2300);
FORCEPROP 1 LAST PATH I54
J 0
(2775 2300);
DISPLAY 0.617021 (2775 2300);
PAINT GREEN (2775 2300);
DISPLAY INVISIBLE (2775 2300);
FORCEADD RES..2
(2775 2150);
FORCEPROP 1 LAST VALUE 4.75K
J 0
(2820 2225);
DISPLAY 0.617021 (2820 2225);
PAINT SKYBLUE (2820 2225);
FORCEPROP 0 LAST POP NOPOP
J 0
(2825 1925);
DISPLAY 0.638298 (2825 1925);
PAINT RED (2825 1925);
FORCEPROP 1 LAST MATERIAL CHIP
J 0
(2815 2075);
DISPLAY 0.617021 (2815 2075);
PAINT SKYBLUE (2815 2075);
FORCEPROP 1 LASTPIN (2775 2050) $PN 2
J 0
(2780 2060);
DISPLAY 0.617021 (2780 2060);
PAINT ORANGE (2780 2060);
FORCEPROP 1 LAST PACK_TYPE 0402
J 0
(2815 1975);
DISPLAY 0.617021 (2815 1975);
PAINT SKYBLUE (2815 1975);
FORCEPROP 1 LAST WATTAGE 1/16W
J 0
(2815 2125);
DISPLAY 0.617021 (2815 2125);
PAINT SKYBLUE (2815 2125);
FORCEPROP 1 LAST TOLERANCE 1%
J 0
(2820 2175);
DISPLAY 0.617021 (2820 2175);
PAINT SKYBLUE (2820 2175);
FORCEPROP 1 LASTPIN (2775 2250) $PN 1
J 0
(2780 2212);
DISPLAY 0.617021 (2780 2212);
PAINT ORANGE (2780 2212);
FORCEPROP 1 LAST LOCATION R9F29
J 0
(2820 2275);
DISPLAY 0.617021 (2820 2275);
PAINT AQUA (2820 2275);
FORCEPROP 1 LAST PART_NUMBER G21796-072
J 0
(2815 2025);
DISPLAY 0.617021 (2815 2025);
PAINT BLUE (2815 2025);
FORCEPROP 0 LAST CDS_SEC 1
J 0
(2825 2325);
PAINT MONO (2825 2325);
DISPLAY INVISIBLE (2825 2325);
FORCEPROP 2 LAST ROOM BMC_MEMORY
J 0
(2825 2325);
DISPLAY 1.021277 (2825 2325);
PAINT ORANGE (2825 2325);
DISPLAY INVISIBLE (2825 2325);
FORCEPROP 2 LAST CDS_LOCATION R9F29
J 0
(2820 2275);
DISPLAY 0.617021 (2820 2275);
PAINT AQUA (2820 2275);
DISPLAY INVISIBLE (2820 2275);
FORCEPROP 2 LAST SEC 1
J 0
(2825 2375);
DISPLAY 0.680851 (2825 2375);
PAINT MONO (2825 2375);
DISPLAY INVISIBLE (2825 2375);
FORCEPROP 2 LAST BOM_COST SM_MEM
J 0
(2825 2375);
DISPLAY 1.021277 (2825 2375);
PAINT ORANGE (2825 2375);
DISPLAY INVISIBLE (2825 2375);
FORCEPROP 2 LAST CDS_LIB mstr_discrete
J 0
(2775 2150);
PAINT ORANGE (2775 2150);
DISPLAY INVISIBLE (2775 2150);
FORCEPROP 2 LAST SEC_TYPE 0402
J 0
(2825 2375);
DISPLAY 1.021277 (2825 2375);
PAINT ORANGE (2825 2375);
DISPLAY INVISIBLE (2825 2375);
FORCEPROP 1 LAST PATH I55
J 0
(2825 2325);
DISPLAY 0.978723 (2825 2325);
PAINT WHITE (2825 2325);
DISPLAY INVISIBLE (2825 2325);
FORCEADD TTL1G07_A..1
(2025 1975);
FORCEPROP 0 LAST POP NOPOP
J 0
(2200 1800);
DISPLAY 0.638298 (2200 1800);
PAINT RED (2200 1800);
FORCEPROP 2 LASTPIN (2175 1975) $PN 4
J 0
(2185 1985);
DISPLAY 0.617021 (2185 1985);
PAINT ORANGE (2185 1985);
FORCEPROP 1 LAST VALUE 74LVC1G07
J 1
(2025 2075);
DISPLAY 0.617021 (2025 2075);
PAINT SKYBLUE (2025 2075);
FORCEPROP 1 LAST PART_NUMBER C88419-001
J 0
(1975 1840);
DISPLAY 0.617021 (1975 1840);
PAINT BLUE (1975 1840);
FORCEPROP 1 LAST POWER_GROUP VCC=P3V3_STBY;GND=GND
J 1
(1975 1785);
DISPLAY 0.617021 (1975 1785);
PAINT ORANGE (1975 1785);
FORCEPROP 1 LAST LOCATION U9F3
J 0
(1975 2175);
DISPLAY 0.617021 (1975 2175);
PAINT AQUA (1975 2175);
FORCEPROP 2 LASTPIN (1925 1975) $PN 2
J 2
(1915 1985);
DISPLAY 0.617021 (1915 1985);
PAINT ORANGE (1915 1985);
FORCEPROP 1 LAST MATERIAL IC
J 0
(1975 2125);
DISPLAY 0.617021 (1975 2125);
PAINT SKYBLUE (1975 2125);
FORCEPROP 1 LAST PACK_TYPE SOP
J 0
(1975 2225);
DISPLAY 0.978723 (1975 2225);
PAINT SKYBLUE (1975 2225);
DISPLAY INVISIBLE (1975 2225);
FORCEPROP 2 LAST CDS_LIB mstr_ttl
J 0
(2025 1975);
PAINT ORANGE (2025 1975);
DISPLAY INVISIBLE (2025 1975);
FORCEPROP 2 LAST SEC_TYPE SOP
J 0
(1975 2225);
DISPLAY 1.021277 (1975 2225);
PAINT ORANGE (1975 2225);
DISPLAY INVISIBLE (1975 2225);
FORCEPROP 2 LAST SEC 1
J 0
(1975 2225);
DISPLAY 0.680851 (1975 2225);
PAINT MONO (1975 2225);
DISPLAY INVISIBLE (1975 2225);
FORCEPROP 2 LAST CDS_LOCATION U9F3
J 0
(1975 2175);
DISPLAY 0.617021 (1975 2175);
PAINT AQUA (1975 2175);
DISPLAY INVISIBLE (1975 2175);
FORCEPROP 0 LAST ROOM BMC_MEMORY
J 0
(1975 2275);
DISPLAY 1.021277 (1975 2275);
PAINT ORANGE (1975 2275);
DISPLAY INVISIBLE (1975 2275);
FORCEPROP 0 LAST CDS_SEC 1
J 0
(1975 2225);
PAINT MONO (1975 2225);
DISPLAY INVISIBLE (1975 2225);
FORCEPROP 1 LAST PATH I56
J 0
(2075 2025);
DISPLAY 0.978723 (2075 2025);
PAINT WHITE (2075 2025);
DISPLAY INVISIBLE (2075 2025);
FORCEADD OFFPAGE..1
(1150 1975);
FORCEPROP 2 LAST $XR0 157 
J 0
(898 1975);
DISPLAY 0.638298 (898 1975);
PAINT MONO (898 1975);
FORCEPROP 1 LAST COMMENT_BODY TRUE
J 0
(1275 1875);
DISPLAY 0.872340 (1275 1875);
PAINT GREEN (1275 1875);
DISPLAY INVISIBLE (1275 1875);
FORCEPROP 1 LAST OFFPAGE TRUE
J 0
(1475 1850);
DISPLAY 0.872340 (1475 1850);
PAINT GREEN (1475 1850);
DISPLAY INVISIBLE (1475 1850);
FORCEPROP 2 LAST CDS_LIB mstr_standard
J 0
(1150 1975);
PAINT ORANGE (1150 1975);
DISPLAY INVISIBLE (1150 1975);
FORCEPROP 2 LAST PATH I57
J 0
(900 2025);
DISPLAY 1.021277 (900 2025);
PAINT ORANGE (900 2025);
DISPLAY INVISIBLE (900 2025);
FORCEADD CAP..1
(-2075 2100);
FORCEPROP 1 LAST PACK_TYPE 0402LF
J 0
(-2025 1925);
DISPLAY 0.617021 (-2025 1925);
PAINT SKYBLUE (-2025 1925);
FORCEPROP 1 LAST VOLTAGE 50V
J 0
(-2025 2075);
DISPLAY 0.617021 (-2025 2075);
PAINT SKYBLUE (-2025 2075);
FORCEPROP 1 LAST TOLERANCE 5%
J 0
(-2025 2025);
DISPLAY 0.617021 (-2025 2025);
PAINT SKYBLUE (-2025 2025);
FORCEPROP 1 LAST VALUE 100.0PF
J 0
(-2025 2125);
DISPLAY 0.617021 (-2025 2125);
PAINT SKYBLUE (-2025 2125);
FORCEPROP 1 LASTPIN (-2075 2000) $PN 2
J 0
(-2065 1980);
DISPLAY 0.787234 (-2065 1980);
PAINT ORANGE (-2065 1980);
FORCEPROP 1 LASTPIN (-2075 2200) $PN 1
J 0
(-2065 2180);
DISPLAY 0.787234 (-2065 2180);
PAINT ORANGE (-2065 2180);
FORCEPROP 1 LAST PART_NUMBER A36095-026
J 0
(-2025 2225);
DISPLAY 0.617021 (-2025 2225);
PAINT BLUE (-2025 2225);
FORCEPROP 1 LAST LOCATION C25W16
J 0
(-2025 2175);
DISPLAY 0.617021 (-2025 2175);
PAINT AQUA (-2025 2175);
FORCEPROP 1 LAST MATERIAL COG
J 0
(-2025 1975);
DISPLAY 0.617021 (-2025 1975);
PAINT SKYBLUE (-2025 1975);
FORCEPROP 2 LAST CDS_LIB mstr_discrete
J 0
(-2075 2100);
PAINT MONO (-2075 2100);
DISPLAY INVISIBLE (-2075 2100);
FORCEPROP 0 LAST ROOM BMC
J 0
(-2025 2250);
DISPLAY 1.021277 (-2025 2250);
PAINT ORANGE (-2025 2250);
DISPLAY INVISIBLE (-2025 2250);
FORCEPROP 0 LAST BOM_COST SM_CONTROLLER
J 0
(-2025 2300);
DISPLAY 1.021277 (-2025 2300);
PAINT ORANGE (-2025 2300);
DISPLAY INVISIBLE (-2025 2300);
FORCEPROP 0 LAST CDS_LOCATION C25W16
J 0
(-2025 2275);
PAINT MONO (-2025 2275);
DISPLAY INVISIBLE (-2025 2275);
FORCEPROP 1 LAST PATH I58
J 0
(-2025 2250);
DISPLAY 0.978723 (-2025 2250);
PAINT WHITE (-2025 2250);
DISPLAY INVISIBLE (-2025 2250);
FORCEPROP 0 LAST SEC 1
J 0
(-2025 2275);
PAINT MONO (-2025 2275);
DISPLAY INVISIBLE (-2025 2275);
FORCEPROP 2 LAST SEC_TYPE 0402LF
J 0
(-2025 2300);
DISPLAY 1.021277 (-2025 2300);
PAINT ORANGE (-2025 2300);
DISPLAY INVISIBLE (-2025 2300);
FORCEADD OFFPAGE..3
(3800 1400);
FORCEPROP 2 LAST $XR1 151 
J 0
(4134 1400);
DISPLAY 0.638298 (4134 1400);
PAINT MONO (4134 1400);
FORCEPROP 2 LAST $XR0 143 
J 0
(4014 1400);
DISPLAY 0.638298 (4014 1400);
PAINT MONO (4014 1400);
FORCEPROP 1 LAST COMMENT_BODY TRUE
J 0
(3750 1300);
DISPLAY 0.872340 (3750 1300);
PAINT GREEN (3750 1300);
DISPLAY INVISIBLE (3750 1300);
FORCEPROP 1 LAST OFFPAGE TRUE
J 0
(4125 1275);
DISPLAY 0.872340 (4125 1275);
PAINT GREEN (4125 1275);
DISPLAY INVISIBLE (4125 1275);
FORCEPROP 2 LAST CDS_LIB mstr_standard
J 0
(3800 1400);
PAINT MONO (3800 1400);
DISPLAY INVISIBLE (3800 1400);
FORCEPROP 2 LAST PATH I59
J 0
(4150 1450);
DISPLAY 1.021277 (4150 1450);
PAINT ORANGE (4150 1450);
DISPLAY INVISIBLE (4150 1450);
FORCEADD OFFPAGE..3
(3800 1450);
FORCEPROP 2 LAST $XR1 151 
J 0
(4134 1450);
DISPLAY 0.638298 (4134 1450);
PAINT MONO (4134 1450);
FORCEPROP 2 LAST $XR0 143 
J 0
(4014 1450);
DISPLAY 0.638298 (4014 1450);
PAINT MONO (4014 1450);
FORCEPROP 1 LAST COMMENT_BODY TRUE
J 0
(3750 1350);
DISPLAY 0.872340 (3750 1350);
PAINT GREEN (3750 1350);
DISPLAY INVISIBLE (3750 1350);
FORCEPROP 1 LAST OFFPAGE TRUE
J 0
(4125 1325);
DISPLAY 0.872340 (4125 1325);
PAINT GREEN (4125 1325);
DISPLAY INVISIBLE (4125 1325);
FORCEPROP 2 LAST CDS_LIB mstr_standard
J 0
(3800 1450);
PAINT MONO (3800 1450);
DISPLAY INVISIBLE (3800 1450);
FORCEPROP 2 LAST PATH I60
J 0
(4150 1500);
DISPLAY 1.021277 (4150 1500);
PAINT ORANGE (4150 1500);
DISPLAY INVISIBLE (4150 1500);
FORCEADD OFFPAGE..3
(3800 1350);
FORCEPROP 2 LAST $XR1 151 
J 0
(4134 1350);
DISPLAY 0.638298 (4134 1350);
PAINT MONO (4134 1350);
FORCEPROP 2 LAST $XR0 143 
J 0
(4014 1350);
DISPLAY 0.638298 (4014 1350);
PAINT MONO (4014 1350);
FORCEPROP 1 LAST COMMENT_BODY TRUE
J 0
(3750 1250);
DISPLAY 0.872340 (3750 1250);
PAINT GREEN (3750 1250);
DISPLAY INVISIBLE (3750 1250);
FORCEPROP 1 LAST OFFPAGE TRUE
J 0
(4125 1225);
DISPLAY 0.872340 (4125 1225);
PAINT GREEN (4125 1225);
DISPLAY INVISIBLE (4125 1225);
FORCEPROP 2 LAST CDS_LIB mstr_standard
J 0
(3800 1350);
PAINT MONO (3800 1350);
DISPLAY INVISIBLE (3800 1350);
FORCEPROP 2 LAST PATH I61
J 0
(4150 1400);
DISPLAY 1.021277 (4150 1400);
PAINT ORANGE (4150 1400);
DISPLAY INVISIBLE (4150 1400);
FORCEADD OFFPAGE..3
(3800 1300);
FORCEPROP 2 LAST $XR1 151 
J 0
(4134 1300);
DISPLAY 0.638298 (4134 1300);
PAINT MONO (4134 1300);
FORCEPROP 2 LAST $XR0 143 
J 0
(4014 1300);
DISPLAY 0.638298 (4014 1300);
PAINT MONO (4014 1300);
FORCEPROP 1 LAST COMMENT_BODY TRUE
J 0
(3750 1200);
DISPLAY 0.872340 (3750 1200);
PAINT GREEN (3750 1200);
DISPLAY INVISIBLE (3750 1200);
FORCEPROP 1 LAST OFFPAGE TRUE
J 0
(4125 1175);
DISPLAY 0.872340 (4125 1175);
PAINT GREEN (4125 1175);
DISPLAY INVISIBLE (4125 1175);
FORCEPROP 2 LAST CDS_LIB mstr_standard
J 0
(3800 1300);
PAINT MONO (3800 1300);
DISPLAY INVISIBLE (3800 1300);
FORCEPROP 2 LAST PATH I62
J 0
(4150 1350);
DISPLAY 1.021277 (4150 1350);
PAINT ORANGE (4150 1350);
DISPLAY INVISIBLE (4150 1350);
FORCEADD OFFPAGE..3
(3800 1250);
FORCEPROP 2 LAST $XR1 151 
J 0
(4134 1250);
DISPLAY 0.638298 (4134 1250);
PAINT MONO (4134 1250);
FORCEPROP 2 LAST $XR0 143 
J 0
(4014 1250);
DISPLAY 0.638298 (4014 1250);
PAINT MONO (4014 1250);
FORCEPROP 1 LAST COMMENT_BODY TRUE
J 0
(3750 1150);
DISPLAY 0.872340 (3750 1150);
PAINT GREEN (3750 1150);
DISPLAY INVISIBLE (3750 1150);
FORCEPROP 1 LAST OFFPAGE TRUE
J 0
(4125 1125);
DISPLAY 0.872340 (4125 1125);
PAINT GREEN (4125 1125);
DISPLAY INVISIBLE (4125 1125);
FORCEPROP 2 LAST CDS_LIB mstr_standard
J 0
(3800 1250);
PAINT MONO (3800 1250);
DISPLAY INVISIBLE (3800 1250);
FORCEPROP 2 LAST PATH I63
J 0
(4150 1300);
DISPLAY 1.021277 (4150 1300);
PAINT ORANGE (4150 1300);
DISPLAY INVISIBLE (4150 1300);
FORCEADD OFFPAGE..3
(3800 1050);
FORCEPROP 2 LAST $XR1 151 
J 0
(4134 1050);
DISPLAY 0.638298 (4134 1050);
PAINT MONO (4134 1050);
FORCEPROP 2 LAST $XR0 143 
J 0
(4014 1050);
DISPLAY 0.638298 (4014 1050);
PAINT MONO (4014 1050);
FORCEPROP 1 LAST COMMENT_BODY TRUE
J 0
(3750 950);
DISPLAY 0.872340 (3750 950);
PAINT GREEN (3750 950);
DISPLAY INVISIBLE (3750 950);
FORCEPROP 1 LAST OFFPAGE TRUE
J 0
(4125 925);
DISPLAY 0.872340 (4125 925);
PAINT GREEN (4125 925);
DISPLAY INVISIBLE (4125 925);
FORCEPROP 2 LAST CDS_LIB mstr_standard
J 0
(3800 1050);
PAINT MONO (3800 1050);
DISPLAY INVISIBLE (3800 1050);
FORCEPROP 2 LAST PATH I64
J 0
(4150 1100);
DISPLAY 1.021277 (4150 1100);
PAINT ORANGE (4150 1100);
DISPLAY INVISIBLE (4150 1100);
FORCEADD OFFPAGE..3
(3800 1100);
FORCEPROP 2 LAST $XR1 151 
J 0
(4134 1100);
DISPLAY 0.638298 (4134 1100);
PAINT MONO (4134 1100);
FORCEPROP 2 LAST $XR0 143 
J 0
(4014 1100);
DISPLAY 0.638298 (4014 1100);
PAINT MONO (4014 1100);
FORCEPROP 1 LAST COMMENT_BODY TRUE
J 0
(3750 1000);
DISPLAY 0.872340 (3750 1000);
PAINT GREEN (3750 1000);
DISPLAY INVISIBLE (3750 1000);
FORCEPROP 1 LAST OFFPAGE TRUE
J 0
(4125 975);
DISPLAY 0.872340 (4125 975);
PAINT GREEN (4125 975);
DISPLAY INVISIBLE (4125 975);
FORCEPROP 2 LAST CDS_LIB mstr_standard
J 0
(3800 1100);
PAINT MONO (3800 1100);
DISPLAY INVISIBLE (3800 1100);
FORCEPROP 2 LAST PATH I65
J 0
(4150 1150);
DISPLAY 1.021277 (4150 1150);
PAINT ORANGE (4150 1150);
DISPLAY INVISIBLE (4150 1150);
FORCEADD OFFPAGE..3
(3800 1200);
FORCEPROP 2 LAST $XR1 151 
J 0
(4134 1200);
DISPLAY 0.638298 (4134 1200);
PAINT MONO (4134 1200);
FORCEPROP 2 LAST $XR0 143 
J 0
(4014 1200);
DISPLAY 0.638298 (4014 1200);
PAINT MONO (4014 1200);
FORCEPROP 1 LAST COMMENT_BODY TRUE
J 0
(3750 1100);
DISPLAY 0.872340 (3750 1100);
PAINT GREEN (3750 1100);
DISPLAY INVISIBLE (3750 1100);
FORCEPROP 1 LAST OFFPAGE TRUE
J 0
(4125 1075);
DISPLAY 0.872340 (4125 1075);
PAINT GREEN (4125 1075);
DISPLAY INVISIBLE (4125 1075);
FORCEPROP 2 LAST CDS_LIB mstr_standard
J 0
(3800 1200);
PAINT MONO (3800 1200);
DISPLAY INVISIBLE (3800 1200);
FORCEPROP 2 LAST PATH I66
J 0
(4150 1250);
DISPLAY 1.021277 (4150 1250);
PAINT ORANGE (4150 1250);
DISPLAY INVISIBLE (4150 1250);
FORCEADD OFFPAGE..3
(3800 1150);
FORCEPROP 2 LAST $XR1 151 
J 0
(4134 1150);
DISPLAY 0.638298 (4134 1150);
PAINT MONO (4134 1150);
FORCEPROP 2 LAST $XR0 143 
J 0
(4014 1150);
DISPLAY 0.638298 (4014 1150);
PAINT MONO (4014 1150);
FORCEPROP 1 LAST COMMENT_BODY TRUE
J 0
(3750 1050);
DISPLAY 0.872340 (3750 1050);
PAINT GREEN (3750 1050);
DISPLAY INVISIBLE (3750 1050);
FORCEPROP 1 LAST OFFPAGE TRUE
J 0
(4125 1025);
DISPLAY 0.872340 (4125 1025);
PAINT GREEN (4125 1025);
DISPLAY INVISIBLE (4125 1025);
FORCEPROP 2 LAST CDS_LIB mstr_standard
J 0
(3800 1150);
PAINT MONO (3800 1150);
DISPLAY INVISIBLE (3800 1150);
FORCEPROP 2 LAST PATH I67
J 0
(4150 1200);
DISPLAY 1.021277 (4150 1200);
PAINT ORANGE (4150 1200);
DISPLAY INVISIBLE (4150 1200);
FORCEADD OFFPAGE..3
(3800 1000);
FORCEPROP 2 LAST $XR1 151 
J 0
(4134 1000);
DISPLAY 0.638298 (4134 1000);
PAINT MONO (4134 1000);
FORCEPROP 2 LAST $XR0 143 
J 0
(4014 1000);
DISPLAY 0.638298 (4014 1000);
PAINT MONO (4014 1000);
FORCEPROP 1 LAST COMMENT_BODY TRUE
J 0
(3750 900);
DISPLAY 0.872340 (3750 900);
PAINT GREEN (3750 900);
DISPLAY INVISIBLE (3750 900);
FORCEPROP 1 LAST OFFPAGE TRUE
J 0
(4125 875);
DISPLAY 0.872340 (4125 875);
PAINT GREEN (4125 875);
DISPLAY INVISIBLE (4125 875);
FORCEPROP 2 LAST CDS_LIB mstr_standard
J 0
(3800 1000);
PAINT MONO (3800 1000);
DISPLAY INVISIBLE (3800 1000);
FORCEPROP 2 LAST PATH I68
J 0
(4150 1050);
DISPLAY 1.021277 (4150 1050);
PAINT ORANGE (4150 1050);
DISPLAY INVISIBLE (4150 1050);
FORCEADD OFFPAGE..3
(3800 950);
FORCEPROP 2 LAST $XR1 151 
J 0
(4134 950);
DISPLAY 0.638298 (4134 950);
PAINT MONO (4134 950);
FORCEPROP 2 LAST $XR0 143 
J 0
(4014 950);
DISPLAY 0.638298 (4014 950);
PAINT MONO (4014 950);
FORCEPROP 1 LAST COMMENT_BODY TRUE
J 0
(3750 850);
DISPLAY 0.872340 (3750 850);
PAINT GREEN (3750 850);
DISPLAY INVISIBLE (3750 850);
FORCEPROP 1 LAST OFFPAGE TRUE
J 0
(4125 825);
DISPLAY 0.872340 (4125 825);
PAINT GREEN (4125 825);
DISPLAY INVISIBLE (4125 825);
FORCEPROP 2 LAST CDS_LIB mstr_standard
J 0
(3800 950);
PAINT MONO (3800 950);
DISPLAY INVISIBLE (3800 950);
FORCEPROP 2 LAST PATH I69
J 0
(4150 1000);
DISPLAY 1.021277 (4150 1000);
PAINT ORANGE (4150 1000);
DISPLAY INVISIBLE (4150 1000);
FORCEADD OFFPAGE..3
(3800 900);
FORCEPROP 2 LAST $XR1 151 
J 0
(4134 900);
DISPLAY 0.638298 (4134 900);
PAINT MONO (4134 900);
FORCEPROP 2 LAST $XR0 143 
J 0
(4014 900);
DISPLAY 0.638298 (4014 900);
PAINT MONO (4014 900);
FORCEPROP 1 LAST COMMENT_BODY TRUE
J 0
(3750 800);
DISPLAY 0.872340 (3750 800);
PAINT GREEN (3750 800);
DISPLAY INVISIBLE (3750 800);
FORCEPROP 1 LAST OFFPAGE TRUE
J 0
(4125 775);
DISPLAY 0.872340 (4125 775);
PAINT GREEN (4125 775);
DISPLAY INVISIBLE (4125 775);
FORCEPROP 2 LAST CDS_LIB mstr_standard
J 0
(3800 900);
PAINT MONO (3800 900);
DISPLAY INVISIBLE (3800 900);
FORCEPROP 2 LAST PATH I70
J 0
(4150 950);
DISPLAY 1.021277 (4150 950);
PAINT ORANGE (4150 950);
DISPLAY INVISIBLE (4150 950);
FORCEADD OFFPAGE..3
(3800 800);
FORCEPROP 2 LAST $XR1 151 
J 0
(4134 800);
DISPLAY 0.638298 (4134 800);
PAINT MONO (4134 800);
FORCEPROP 2 LAST $XR0 143 
J 0
(4014 800);
DISPLAY 0.638298 (4014 800);
PAINT MONO (4014 800);
FORCEPROP 1 LAST COMMENT_BODY TRUE
J 0
(3750 700);
DISPLAY 0.872340 (3750 700);
PAINT GREEN (3750 700);
DISPLAY INVISIBLE (3750 700);
FORCEPROP 1 LAST OFFPAGE TRUE
J 0
(4125 675);
DISPLAY 0.872340 (4125 675);
PAINT GREEN (4125 675);
DISPLAY INVISIBLE (4125 675);
FORCEPROP 2 LAST CDS_LIB mstr_standard
J 0
(3800 800);
PAINT MONO (3800 800);
DISPLAY INVISIBLE (3800 800);
FORCEPROP 2 LAST PATH I71
J 0
(4150 850);
DISPLAY 1.021277 (4150 850);
PAINT ORANGE (4150 850);
DISPLAY INVISIBLE (4150 850);
FORCEADD OFFPAGE..3
(3800 850);
FORCEPROP 2 LAST $XR1 151 
J 0
(4134 850);
DISPLAY 0.638298 (4134 850);
PAINT MONO (4134 850);
FORCEPROP 2 LAST $XR0 143 
J 0
(4014 850);
DISPLAY 0.638298 (4014 850);
PAINT MONO (4014 850);
FORCEPROP 1 LAST COMMENT_BODY TRUE
J 0
(3750 750);
DISPLAY 0.872340 (3750 750);
PAINT GREEN (3750 750);
DISPLAY INVISIBLE (3750 750);
FORCEPROP 1 LAST OFFPAGE TRUE
J 0
(4125 725);
DISPLAY 0.872340 (4125 725);
PAINT GREEN (4125 725);
DISPLAY INVISIBLE (4125 725);
FORCEPROP 2 LAST CDS_LIB mstr_standard
J 0
(3800 850);
PAINT MONO (3800 850);
DISPLAY INVISIBLE (3800 850);
FORCEPROP 2 LAST PATH I72
J 0
(4150 900);
DISPLAY 1.021277 (4150 900);
PAINT ORANGE (4150 900);
DISPLAY INVISIBLE (4150 900);
FORCEADD OFFPAGE..3
(3800 750);
FORCEPROP 2 LAST $XR1 151 
J 0
(4134 750);
DISPLAY 0.638298 (4134 750);
PAINT MONO (4134 750);
FORCEPROP 2 LAST $XR0 143 
J 0
(4014 750);
DISPLAY 0.638298 (4014 750);
PAINT MONO (4014 750);
FORCEPROP 1 LAST COMMENT_BODY TRUE
J 0
(3750 650);
DISPLAY 0.872340 (3750 650);
PAINT GREEN (3750 650);
DISPLAY INVISIBLE (3750 650);
FORCEPROP 1 LAST OFFPAGE TRUE
J 0
(4125 625);
DISPLAY 0.872340 (4125 625);
PAINT GREEN (4125 625);
DISPLAY INVISIBLE (4125 625);
FORCEPROP 2 LAST CDS_LIB mstr_standard
J 0
(3800 750);
PAINT MONO (3800 750);
DISPLAY INVISIBLE (3800 750);
FORCEPROP 2 LAST PATH I73
J 0
(4150 800);
DISPLAY 1.021277 (4150 800);
PAINT ORANGE (4150 800);
DISPLAY INVISIBLE (4150 800);
FORCEADD OFFPAGE..3
(3800 700);
FORCEPROP 2 LAST $XR1 151 
J 0
(4134 700);
DISPLAY 0.638298 (4134 700);
PAINT MONO (4134 700);
FORCEPROP 2 LAST $XR0 143 
J 0
(4014 700);
DISPLAY 0.638298 (4014 700);
PAINT MONO (4014 700);
FORCEPROP 1 LAST COMMENT_BODY TRUE
J 0
(3750 600);
DISPLAY 0.872340 (3750 600);
PAINT GREEN (3750 600);
DISPLAY INVISIBLE (3750 600);
FORCEPROP 1 LAST OFFPAGE TRUE
J 0
(4125 575);
DISPLAY 0.872340 (4125 575);
PAINT GREEN (4125 575);
DISPLAY INVISIBLE (4125 575);
FORCEPROP 2 LAST CDS_LIB mstr_standard
J 0
(3800 700);
PAINT MONO (3800 700);
DISPLAY INVISIBLE (3800 700);
FORCEPROP 2 LAST PATH I74
J 0
(4150 750);
DISPLAY 1.021277 (4150 750);
PAINT ORANGE (4150 750);
DISPLAY INVISIBLE (4150 750);
FORCEADD OFFPAGE..3
(3800 650);
FORCEPROP 2 LAST $XR1 151 
J 0
(4134 650);
DISPLAY 0.638298 (4134 650);
PAINT MONO (4134 650);
FORCEPROP 2 LAST $XR0 143 
J 0
(4014 650);
DISPLAY 0.638298 (4014 650);
PAINT MONO (4014 650);
FORCEPROP 1 LAST COMMENT_BODY TRUE
J 0
(3750 550);
DISPLAY 0.872340 (3750 550);
PAINT GREEN (3750 550);
DISPLAY INVISIBLE (3750 550);
FORCEPROP 1 LAST OFFPAGE TRUE
J 0
(4125 525);
DISPLAY 0.872340 (4125 525);
PAINT GREEN (4125 525);
DISPLAY INVISIBLE (4125 525);
FORCEPROP 2 LAST CDS_LIB mstr_standard
J 0
(3800 650);
PAINT MONO (3800 650);
DISPLAY INVISIBLE (3800 650);
FORCEPROP 2 LAST PATH I75
J 0
(4150 700);
DISPLAY 1.021277 (4150 700);
PAINT ORANGE (4150 700);
DISPLAY INVISIBLE (4150 700);
FORCEADD OFFPAGE..3
(3800 550);
FORCEPROP 2 LAST $XR1 151 
J 0
(4134 550);
DISPLAY 0.638298 (4134 550);
PAINT MONO (4134 550);
FORCEPROP 2 LAST $XR0 143 
J 0
(4014 550);
DISPLAY 0.638298 (4014 550);
PAINT MONO (4014 550);
FORCEPROP 1 LAST COMMENT_BODY TRUE
J 0
(3750 450);
DISPLAY 0.872340 (3750 450);
PAINT GREEN (3750 450);
DISPLAY INVISIBLE (3750 450);
FORCEPROP 1 LAST OFFPAGE TRUE
J 0
(4125 425);
DISPLAY 0.872340 (4125 425);
PAINT GREEN (4125 425);
DISPLAY INVISIBLE (4125 425);
FORCEPROP 2 LAST CDS_LIB mstr_standard
J 0
(3800 550);
PAINT MONO (3800 550);
DISPLAY INVISIBLE (3800 550);
FORCEPROP 2 LAST PATH I76
J 0
(4150 600);
DISPLAY 1.021277 (4150 600);
PAINT ORANGE (4150 600);
DISPLAY INVISIBLE (4150 600);
FORCEADD OFFPAGE..3
(3800 500);
FORCEPROP 2 LAST $XR1 151 
J 0
(4134 500);
DISPLAY 0.638298 (4134 500);
PAINT MONO (4134 500);
FORCEPROP 2 LAST $XR0 143 
J 0
(4014 500);
DISPLAY 0.638298 (4014 500);
PAINT MONO (4014 500);
FORCEPROP 1 LAST COMMENT_BODY TRUE
J 0
(3750 400);
DISPLAY 0.872340 (3750 400);
PAINT GREEN (3750 400);
DISPLAY INVISIBLE (3750 400);
FORCEPROP 1 LAST OFFPAGE TRUE
J 0
(4125 375);
DISPLAY 0.872340 (4125 375);
PAINT GREEN (4125 375);
DISPLAY INVISIBLE (4125 375);
FORCEPROP 2 LAST CDS_LIB mstr_standard
J 0
(3800 500);
PAINT MONO (3800 500);
DISPLAY INVISIBLE (3800 500);
FORCEPROP 2 LAST PATH I77
J 0
(4150 550);
DISPLAY 1.021277 (4150 550);
PAINT ORANGE (4150 550);
DISPLAY INVISIBLE (4150 550);
FORCEADD OFFPAGE..3
(3800 450);
FORCEPROP 2 LAST $XR1 151 
J 0
(4134 450);
DISPLAY 0.638298 (4134 450);
PAINT MONO (4134 450);
FORCEPROP 2 LAST $XR0 143 
J 0
(4014 450);
DISPLAY 0.638298 (4014 450);
PAINT MONO (4014 450);
FORCEPROP 1 LAST COMMENT_BODY TRUE
J 0
(3750 350);
DISPLAY 0.872340 (3750 350);
PAINT GREEN (3750 350);
DISPLAY INVISIBLE (3750 350);
FORCEPROP 1 LAST OFFPAGE TRUE
J 0
(4125 325);
DISPLAY 0.872340 (4125 325);
PAINT GREEN (4125 325);
DISPLAY INVISIBLE (4125 325);
FORCEPROP 2 LAST CDS_LIB mstr_standard
J 0
(3800 450);
PAINT MONO (3800 450);
DISPLAY INVISIBLE (3800 450);
FORCEPROP 2 LAST PATH I78
J 0
(4150 500);
DISPLAY 1.021277 (4150 500);
PAINT ORANGE (4150 500);
DISPLAY INVISIBLE (4150 500);
FORCEADD OFFPAGE..3
(3800 250);
FORCEPROP 2 LAST $XR1 151 
J 0
(4134 250);
DISPLAY 0.638298 (4134 250);
PAINT MONO (4134 250);
FORCEPROP 2 LAST $XR0 146 
J 0
(4014 250);
DISPLAY 0.638298 (4014 250);
PAINT MONO (4014 250);
FORCEPROP 1 LAST COMMENT_BODY TRUE
J 0
(3750 150);
DISPLAY 0.872340 (3750 150);
PAINT GREEN (3750 150);
DISPLAY INVISIBLE (3750 150);
FORCEPROP 1 LAST OFFPAGE TRUE
J 0
(4125 125);
DISPLAY 0.872340 (4125 125);
PAINT GREEN (4125 125);
DISPLAY INVISIBLE (4125 125);
FORCEPROP 2 LAST CDS_LIB mstr_standard
J 0
(3800 250);
PAINT MONO (3800 250);
DISPLAY INVISIBLE (3800 250);
FORCEPROP 2 LAST PATH I79
J 0
(4150 300);
DISPLAY 1.021277 (4150 300);
PAINT ORANGE (4150 300);
DISPLAY INVISIBLE (4150 300);
FORCEADD OFFPAGE..3
(3800 300);
FORCEPROP 2 LAST $XR1 151 
J 0
(4134 300);
DISPLAY 0.638298 (4134 300);
PAINT MONO (4134 300);
FORCEPROP 2 LAST $XR0 143 
J 0
(4014 300);
DISPLAY 0.638298 (4014 300);
PAINT MONO (4014 300);
FORCEPROP 1 LAST COMMENT_BODY TRUE
J 0
(3750 200);
DISPLAY 0.872340 (3750 200);
PAINT GREEN (3750 200);
DISPLAY INVISIBLE (3750 200);
FORCEPROP 1 LAST OFFPAGE TRUE
J 0
(4125 175);
DISPLAY 0.872340 (4125 175);
PAINT GREEN (4125 175);
DISPLAY INVISIBLE (4125 175);
FORCEPROP 2 LAST CDS_LIB mstr_standard
J 0
(3800 300);
PAINT MONO (3800 300);
DISPLAY INVISIBLE (3800 300);
FORCEPROP 2 LAST PATH I80
J 0
(4150 350);
DISPLAY 1.021277 (4150 350);
PAINT ORANGE (4150 350);
DISPLAY INVISIBLE (4150 350);
FORCEADD OFFPAGE..3
(3800 350);
FORCEPROP 2 LAST $XR1 151 
J 0
(4134 350);
DISPLAY 0.638298 (4134 350);
PAINT MONO (4134 350);
FORCEPROP 2 LAST $XR0 143 
J 0
(4014 350);
DISPLAY 0.638298 (4014 350);
PAINT MONO (4014 350);
FORCEPROP 1 LAST COMMENT_BODY TRUE
J 0
(3750 250);
DISPLAY 0.872340 (3750 250);
PAINT GREEN (3750 250);
DISPLAY INVISIBLE (3750 250);
FORCEPROP 1 LAST OFFPAGE TRUE
J 0
(4125 225);
DISPLAY 0.872340 (4125 225);
PAINT GREEN (4125 225);
DISPLAY INVISIBLE (4125 225);
FORCEPROP 2 LAST CDS_LIB mstr_standard
J 0
(3800 350);
PAINT MONO (3800 350);
DISPLAY INVISIBLE (3800 350);
FORCEPROP 2 LAST PATH I81
J 0
(4150 400);
DISPLAY 1.021277 (4150 400);
PAINT ORANGE (4150 400);
DISPLAY INVISIBLE (4150 400);
FORCEADD OFFPAGE..3
(3800 200);
FORCEPROP 2 LAST $XR1 151 
J 0
(4134 200);
DISPLAY 0.638298 (4134 200);
PAINT MONO (4134 200);
FORCEPROP 2 LAST $XR0 146 
J 0
(4014 200);
DISPLAY 0.638298 (4014 200);
PAINT MONO (4014 200);
FORCEPROP 1 LAST COMMENT_BODY TRUE
J 0
(3750 100);
DISPLAY 0.872340 (3750 100);
PAINT GREEN (3750 100);
DISPLAY INVISIBLE (3750 100);
FORCEPROP 1 LAST OFFPAGE TRUE
J 0
(4125 75);
DISPLAY 0.872340 (4125 75);
PAINT GREEN (4125 75);
DISPLAY INVISIBLE (4125 75);
FORCEPROP 2 LAST CDS_LIB mstr_standard
J 0
(3800 200);
PAINT MONO (3800 200);
DISPLAY INVISIBLE (3800 200);
FORCEPROP 2 LAST PATH I82
J 0
(4150 250);
DISPLAY 1.021277 (4150 250);
PAINT ORANGE (4150 250);
DISPLAY INVISIBLE (4150 250);
FORCEADD OFFPAGE..3
(3800 0);
FORCEPROP 2 LAST $XR1 151 
J 0
(4134 0);
DISPLAY 0.638298 (4134 0);
PAINT MONO (4134 0);
FORCEPROP 2 LAST $XR0 143 
J 0
(4014 0);
DISPLAY 0.638298 (4014 0);
PAINT MONO (4014 0);
FORCEPROP 1 LAST COMMENT_BODY TRUE
J 0
(3750 -100);
DISPLAY 0.872340 (3750 -100);
PAINT GREEN (3750 -100);
DISPLAY INVISIBLE (3750 -100);
FORCEPROP 1 LAST OFFPAGE TRUE
J 0
(4125 -125);
DISPLAY 0.872340 (4125 -125);
PAINT GREEN (4125 -125);
DISPLAY INVISIBLE (4125 -125);
FORCEPROP 2 LAST CDS_LIB mstr_standard
J 0
(3800 0);
PAINT MONO (3800 0);
DISPLAY INVISIBLE (3800 0);
FORCEPROP 2 LAST PATH I83
J 0
(4150 50);
DISPLAY 1.021277 (4150 50);
PAINT ORANGE (4150 50);
DISPLAY INVISIBLE (4150 50);
FORCEADD OFFPAGE..3
(3800 100);
FORCEPROP 2 LAST $XR1 151 
J 0
(4134 100);
DISPLAY 0.638298 (4134 100);
PAINT MONO (4134 100);
FORCEPROP 2 LAST $XR0 143 
J 0
(4014 100);
DISPLAY 0.638298 (4014 100);
PAINT MONO (4014 100);
FORCEPROP 1 LAST COMMENT_BODY TRUE
J 0
(3750 0);
DISPLAY 0.872340 (3750 0);
PAINT GREEN (3750 0);
DISPLAY INVISIBLE (3750 0);
FORCEPROP 1 LAST OFFPAGE TRUE
J 0
(4125 -25);
DISPLAY 0.872340 (4125 -25);
PAINT GREEN (4125 -25);
DISPLAY INVISIBLE (4125 -25);
FORCEPROP 2 LAST CDS_LIB mstr_standard
J 0
(3800 100);
PAINT MONO (3800 100);
DISPLAY INVISIBLE (3800 100);
FORCEPROP 2 LAST PATH I84
J 0
(4150 150);
DISPLAY 1.021277 (4150 150);
PAINT ORANGE (4150 150);
DISPLAY INVISIBLE (4150 150);
FORCEADD GND..1
(3350 -1550);
FORCEPROP 3 LASTPIN (3350 -1500) SIG_NAME GND\g
J 0
(3360 -1490);
DISPLAY 0.659574 (3360 -1490);
PAINT MONO (3360 -1490);
DISPLAY INVISIBLE (3360 -1490);
FORCEPROP 1 LAST HDL_POWER GND
J 0
(3350 -1400);
DISPLAY 0.872340 (3350 -1400);
PAINT GREEN (3350 -1400);
DISPLAY INVISIBLE (3350 -1400);
FORCEPROP 1 LAST BODY_TYPE PLUMBING
J 0
(3305 -1593);
DISPLAY 0.340426 (3305 -1593);
PAINT GREEN (3305 -1593);
DISPLAY INVISIBLE (3305 -1593);
FORCEPROP 1 LAST PATH I85
J 0
(3425 -1550);
DISPLAY 0.872340 (3425 -1550);
PAINT AQUA (3425 -1550);
DISPLAY INVISIBLE (3425 -1550);
FORCEPROP 1 LAST VOLTAGE 0.0V
J 0
(3305 -1593);
DISPLAY 0.340426 (3305 -1593);
PAINT GREEN (3305 -1593);
DISPLAY INVISIBLE (3305 -1593);
FORCEPROP 1 LAST SIZE 1B
J 0
(3425 -1600);
DISPLAY 0.872340 (3425 -1600);
PAINT AQUA (3425 -1600);
DISPLAY INVISIBLE (3425 -1600);
FORCEPROP 2 LAST CDS_LIB mstr_symbols
J 0
(3350 -1550);
PAINT MONO (3350 -1550);
DISPLAY INVISIBLE (3350 -1550);
FORCEADD W_VCC_CIRCLE..1
(1900 1500);
FORCEPROP 3 LASTPIN (1900 1500) SIG_NAME P1V2_AUX_BMC\g
J 0
(1910 1510);
DISPLAY 0.659574 (1910 1510);
PAINT MONO (1910 1510);
DISPLAY INVISIBLE (1910 1510);
FORCEPROP 1 LAST HDL_POWER P1V2_AUX_BMC
J 1
(1921 1575);
DISPLAY 0.872340 (1921 1575);
PAINT ORANGE (1921 1575);
FORCEPROP 1 LAST BODY_TYPE PLUMBING
J 0
(1912 1494);
DISPLAY 0.340426 (1912 1494);
PAINT GREEN (1912 1494);
DISPLAY INVISIBLE (1912 1494);
FORCEPROP 1 LAST PATH I86
J 0
(1900 1500);
DISPLAY 0.617021 (1900 1500);
PAINT GREEN (1900 1500);
DISPLAY INVISIBLE (1900 1500);
FORCEPROP 1 LAST CDS_LMAN_SYM_OUTLINE -100,100,100,-100
J 0
(1900 1500);
DISPLAY 0.468085 (1900 1500);
PAINT GREEN (1900 1500);
DISPLAY INVISIBLE (1900 1500);
FORCEPROP 2 LAST CDS_LIB w_power
J 0
(1900 1500);
PAINT MONO (1900 1500);
DISPLAY INVISIBLE (1900 1500);
FORCEADD W_VCC_CIRCLE..1
(1100 750);
FORCEPROP 3 LASTPIN (1100 750) SIG_NAME P2V5_AUX_BMC\g
J 0
(1110 760);
DISPLAY 0.659574 (1110 760);
PAINT MONO (1110 760);
DISPLAY INVISIBLE (1110 760);
FORCEPROP 1 LAST HDL_POWER P2V5_AUX_BMC
J 1
(1121 825);
DISPLAY 0.872340 (1121 825);
PAINT ORANGE (1121 825);
FORCEPROP 1 LAST BODY_TYPE PLUMBING
J 0
(1112 744);
DISPLAY 0.340426 (1112 744);
PAINT GREEN (1112 744);
DISPLAY INVISIBLE (1112 744);
FORCEPROP 1 LAST CDS_LMAN_SYM_OUTLINE -100,100,100,-100
J 0
(1100 750);
DISPLAY 0.468085 (1100 750);
PAINT GREEN (1100 750);
DISPLAY INVISIBLE (1100 750);
FORCEPROP 2 LAST CDS_LIB w_power
J 0
(1100 750);
PAINT MONO (1100 750);
DISPLAY INVISIBLE (1100 750);
FORCEPROP 1 LAST PATH I88
J 0
(1100 750);
DISPLAY 0.617021 (1100 750);
PAINT GREEN (1100 750);
DISPLAY INVISIBLE (1100 750);
FORCEADD OFFPAGE..3
R 2
(1500 0);
FORCEPROP 2 LAST $XR0 143 
J 0
(1220 0);
DISPLAY 0.638298 (1220 0);
PAINT MONO (1220 0);
FORCEPROP 1 LAST COMMENT_BODY TRUE
J 2
(1550 -100);
DISPLAY 1.170213 (1550 -100);
PAINT GREEN (1550 -100);
DISPLAY INVISIBLE (1550 -100);
FORCEPROP 1 LAST OFFPAGE TRUE
J 2
(1175 -125);
PAINT GREEN (1175 -125);
DISPLAY INVISIBLE (1175 -125);
FORCEPROP 2 LAST BOM_COST SM_CONTROLLER
J 2
(1025 50);
PAINT MONO (1025 50);
DISPLAY INVISIBLE (1025 50);
FORCEPROP 2 LAST ROOM BMC
J 2
(1025 50);
PAINT MONO (1025 50);
DISPLAY INVISIBLE (1025 50);
FORCEPROP 2 LAST CDS_LIB mstr_standard
J 0
(1500 0);
PAINT MONO (1500 0);
DISPLAY INVISIBLE (1500 0);
FORCEPROP 2 LAST PATH I89
J 0
(1200 50);
DISPLAY 1.021277 (1200 50);
PAINT ORANGE (1200 50);
DISPLAY INVISIBLE (1200 50);
FORCEADD GND..1
(1100 200);
FORCEPROP 3 LASTPIN (1100 250) SIG_NAME GND\g
J 0
(1110 260);
DISPLAY 0.659574 (1110 260);
PAINT MONO (1110 260);
DISPLAY INVISIBLE (1110 260);
FORCEPROP 1 LAST HDL_POWER GND
J 0
(1100 350);
DISPLAY 0.872340 (1100 350);
PAINT GREEN (1100 350);
DISPLAY INVISIBLE (1100 350);
FORCEPROP 1 LAST BODY_TYPE PLUMBING
J 0
(1055 157);
DISPLAY 0.340426 (1055 157);
PAINT GREEN (1055 157);
DISPLAY INVISIBLE (1055 157);
FORCEPROP 1 LAST SIZE 1B
J 0
(1175 150);
DISPLAY 0.872340 (1175 150);
PAINT AQUA (1175 150);
DISPLAY INVISIBLE (1175 150);
FORCEPROP 2 LAST CDS_LIB mstr_symbols
J 0
(1100 200);
PAINT MONO (1100 200);
DISPLAY INVISIBLE (1100 200);
FORCEPROP 1 LAST VOLTAGE 0.0V
J 0
(1055 157);
DISPLAY 0.340426 (1055 157);
PAINT GREEN (1055 157);
DISPLAY INVISIBLE (1055 157);
FORCEPROP 1 LAST PATH I91
J 0
(1175 200);
DISPLAY 0.872340 (1175 200);
PAINT AQUA (1175 200);
DISPLAY INVISIBLE (1175 200);
FORCEADD OFFPAGE..3
R 2
(1500 -100);
FORCEPROP 2 LAST $XR0 143 
J 0
(1220 -100);
DISPLAY 0.638298 (1220 -100);
PAINT MONO (1220 -100);
FORCEPROP 1 LAST COMMENT_BODY TRUE
J 2
(1550 -200);
DISPLAY 1.170213 (1550 -200);
PAINT GREEN (1550 -200);
DISPLAY INVISIBLE (1550 -200);
FORCEPROP 1 LAST OFFPAGE TRUE
J 2
(1175 -225);
PAINT GREEN (1175 -225);
DISPLAY INVISIBLE (1175 -225);
FORCEPROP 2 LAST BOM_COST SM_CONTROLLER
J 2
(1025 -50);
PAINT MONO (1025 -50);
DISPLAY INVISIBLE (1025 -50);
FORCEPROP 2 LAST ROOM BMC
J 2
(1025 -50);
PAINT MONO (1025 -50);
DISPLAY INVISIBLE (1025 -50);
FORCEPROP 2 LAST CDS_LIB mstr_standard
J 0
(1500 -100);
PAINT MONO (1500 -100);
DISPLAY INVISIBLE (1500 -100);
FORCEPROP 2 LAST PATH I92
J 0
(1200 -50);
DISPLAY 1.021277 (1200 -50);
PAINT ORANGE (1200 -50);
DISPLAY INVISIBLE (1200 -50);
FORCEADD OFFPAGE..3
R 2
(1500 -50);
FORCEPROP 2 LAST $XR0 143 
J 0
(1220 -50);
DISPLAY 0.638298 (1220 -50);
PAINT MONO (1220 -50);
FORCEPROP 1 LAST COMMENT_BODY TRUE
J 2
(1550 -150);
DISPLAY 1.170213 (1550 -150);
PAINT GREEN (1550 -150);
DISPLAY INVISIBLE (1550 -150);
FORCEPROP 1 LAST OFFPAGE TRUE
J 2
(1175 -175);
PAINT GREEN (1175 -175);
DISPLAY INVISIBLE (1175 -175);
FORCEPROP 2 LAST BOM_COST SM_CONTROLLER
J 2
(1025 0);
PAINT MONO (1025 0);
DISPLAY INVISIBLE (1025 0);
FORCEPROP 2 LAST ROOM BMC
J 2
(1025 0);
PAINT MONO (1025 0);
DISPLAY INVISIBLE (1025 0);
FORCEPROP 2 LAST CDS_LIB mstr_standard
J 0
(1500 -50);
PAINT MONO (1500 -50);
DISPLAY INVISIBLE (1500 -50);
FORCEPROP 2 LAST PATH I93
J 0
(1200 0);
DISPLAY 1.021277 (1200 0);
PAINT ORANGE (1200 0);
DISPLAY INVISIBLE (1200 0);
FORCEADD OFFPAGE..3
R 2
(1500 -150);
FORCEPROP 2 LAST $XR0 143 
J 0
(1220 -150);
DISPLAY 0.638298 (1220 -150);
PAINT MONO (1220 -150);
FORCEPROP 1 LAST COMMENT_BODY TRUE
J 2
(1550 -250);
DISPLAY 1.170213 (1550 -250);
PAINT GREEN (1550 -250);
DISPLAY INVISIBLE (1550 -250);
FORCEPROP 1 LAST OFFPAGE TRUE
J 2
(1175 -275);
PAINT GREEN (1175 -275);
DISPLAY INVISIBLE (1175 -275);
FORCEPROP 2 LAST BOM_COST SM_CONTROLLER
J 2
(1025 -100);
PAINT MONO (1025 -100);
DISPLAY INVISIBLE (1025 -100);
FORCEPROP 2 LAST ROOM BMC
J 2
(1025 -100);
PAINT MONO (1025 -100);
DISPLAY INVISIBLE (1025 -100);
FORCEPROP 2 LAST CDS_LIB mstr_standard
J 0
(1500 -150);
PAINT MONO (1500 -150);
DISPLAY INVISIBLE (1500 -150);
FORCEPROP 2 LAST PATH I94
J 0
(1200 -100);
DISPLAY 1.021277 (1200 -100);
PAINT ORANGE (1200 -100);
DISPLAY INVISIBLE (1200 -100);
FORCEADD OFFPAGE..3
R 2
(1500 -200);
FORCEPROP 2 LAST $XR0 143 
J 0
(830 -200);
DISPLAY 0.638298 (830 -200);
PAINT MONO (830 -200);
FORCEPROP 1 LAST COMMENT_BODY TRUE
J 2
(1550 -300);
DISPLAY 1.170213 (1550 -300);
PAINT GREEN (1550 -300);
DISPLAY INVISIBLE (1550 -300);
FORCEPROP 1 LAST OFFPAGE TRUE
J 2
(1175 -325);
PAINT GREEN (1175 -325);
DISPLAY INVISIBLE (1175 -325);
FORCEPROP 2 LAST BOM_COST SM_CONTROLLER
J 2
(1025 -150);
PAINT MONO (1025 -150);
DISPLAY INVISIBLE (1025 -150);
FORCEPROP 2 LAST ROOM BMC
J 2
(1025 -150);
PAINT MONO (1025 -150);
DISPLAY INVISIBLE (1025 -150);
FORCEPROP 2 LAST CDS_LIB mstr_standard
J 0
(1500 -200);
PAINT MONO (1500 -200);
DISPLAY INVISIBLE (1500 -200);
FORCEPROP 2 LAST PATH I95
J 0
(1200 -150);
DISPLAY 1.021277 (1200 -150);
PAINT ORANGE (1200 -150);
DISPLAY INVISIBLE (1200 -150);
FORCEADD OFFPAGE..3
R 2
(1500 -250);
FORCEPROP 1 LAST COMMENT_BODY TRUE
J 2
(1550 -350);
DISPLAY 1.170213 (1550 -350);
PAINT GREEN (1550 -350);
DISPLAY INVISIBLE (1550 -350);
FORCEPROP 1 LAST OFFPAGE TRUE
J 2
(1175 -375);
PAINT GREEN (1175 -375);
DISPLAY INVISIBLE (1175 -375);
FORCEPROP 2 LAST BOM_COST SM_CONTROLLER
J 2
(1025 -200);
PAINT MONO (1025 -200);
DISPLAY INVISIBLE (1025 -200);
FORCEPROP 2 LAST ROOM BMC
J 2
(1025 -200);
PAINT MONO (1025 -200);
DISPLAY INVISIBLE (1025 -200);
FORCEPROP 2 LAST CDS_LIB mstr_standard
J 0
(1500 -250);
PAINT MONO (1500 -250);
DISPLAY INVISIBLE (1500 -250);
FORCEPROP 2 LAST PATH I96
J 0
(1200 -200);
DISPLAY 1.021277 (1200 -200);
PAINT ORANGE (1200 -200);
DISPLAY INVISIBLE (1200 -200);
FORCEPROP 2 LAST $XR0 143 
J 0
(1046 -250);
DISPLAY 0.638298 (1046 -250);
PAINT MONO (1046 -250);
DISPLAY INVISIBLE (1046 -250);
FORCEADD OFFPAGE..3
R 2
(1500 -300);
FORCEPROP 2 LAST $XR0 143 
J 0
(1220 -300);
DISPLAY 0.638298 (1220 -300);
PAINT MONO (1220 -300);
FORCEPROP 1 LAST COMMENT_BODY TRUE
J 2
(1550 -400);
DISPLAY 1.170213 (1550 -400);
PAINT GREEN (1550 -400);
DISPLAY INVISIBLE (1550 -400);
FORCEPROP 1 LAST OFFPAGE TRUE
J 2
(1175 -425);
PAINT GREEN (1175 -425);
DISPLAY INVISIBLE (1175 -425);
FORCEPROP 2 LAST BOM_COST SM_CONTROLLER
J 2
(1025 -250);
PAINT MONO (1025 -250);
DISPLAY INVISIBLE (1025 -250);
FORCEPROP 2 LAST ROOM BMC
J 2
(1025 -250);
PAINT MONO (1025 -250);
DISPLAY INVISIBLE (1025 -250);
FORCEPROP 2 LAST CDS_LIB mstr_standard
J 0
(1500 -300);
PAINT MONO (1500 -300);
DISPLAY INVISIBLE (1500 -300);
FORCEPROP 2 LAST PATH I97
J 0
(1200 -250);
DISPLAY 1.021277 (1200 -250);
PAINT ORANGE (1200 -250);
DISPLAY INVISIBLE (1200 -250);
FORCEADD OFFPAGE..3
R 2
(1500 -350);
FORCEPROP 2 LAST $XR0 143 
J 0
(1220 -350);
DISPLAY 0.638298 (1220 -350);
PAINT MONO (1220 -350);
FORCEPROP 1 LAST COMMENT_BODY TRUE
J 2
(1550 -450);
DISPLAY 1.170213 (1550 -450);
PAINT GREEN (1550 -450);
DISPLAY INVISIBLE (1550 -450);
FORCEPROP 1 LAST OFFPAGE TRUE
J 2
(1175 -475);
PAINT GREEN (1175 -475);
DISPLAY INVISIBLE (1175 -475);
FORCEPROP 2 LAST BOM_COST SM_CONTROLLER
J 2
(1025 -300);
PAINT MONO (1025 -300);
DISPLAY INVISIBLE (1025 -300);
FORCEPROP 2 LAST ROOM BMC
J 2
(1025 -300);
PAINT MONO (1025 -300);
DISPLAY INVISIBLE (1025 -300);
FORCEPROP 2 LAST CDS_LIB mstr_standard
J 0
(1500 -350);
PAINT MONO (1500 -350);
DISPLAY INVISIBLE (1500 -350);
FORCEPROP 2 LAST PATH I98
J 0
(1200 -300);
DISPLAY 1.021277 (1200 -300);
PAINT ORANGE (1200 -300);
DISPLAY INVISIBLE (1200 -300);
FORCEADD OFFPAGE..3
R 2
(1500 -500);
FORCEPROP 2 LAST $XR0 143 
J 0
(1220 -500);
DISPLAY 0.638298 (1220 -500);
PAINT MONO (1220 -500);
FORCEPROP 1 LAST COMMENT_BODY TRUE
J 2
(1550 -600);
DISPLAY 1.170213 (1550 -600);
PAINT GREEN (1550 -600);
DISPLAY INVISIBLE (1550 -600);
FORCEPROP 1 LAST OFFPAGE TRUE
J 2
(1175 -625);
PAINT GREEN (1175 -625);
DISPLAY INVISIBLE (1175 -625);
FORCEPROP 2 LAST BOM_COST SM_CONTROLLER
J 2
(1025 -450);
PAINT MONO (1025 -450);
DISPLAY INVISIBLE (1025 -450);
FORCEPROP 2 LAST ROOM BMC
J 2
(1025 -450);
PAINT MONO (1025 -450);
DISPLAY INVISIBLE (1025 -450);
FORCEPROP 2 LAST CDS_LIB mstr_standard
J 0
(1500 -500);
PAINT MONO (1500 -500);
DISPLAY INVISIBLE (1500 -500);
FORCEPROP 2 LAST PATH I99
J 0
(1200 -450);
DISPLAY 1.021277 (1200 -450);
PAINT ORANGE (1200 -450);
DISPLAY INVISIBLE (1200 -450);
FORCEADD CAD_NOTE..1
(-1050 -1000);
FORCEPROP 0 LAST L1 PLEASE PLACE LED NEAR BMC
J 0
(-1225 -1125);
DISPLAY 1.021277 (-1225 -1125);
PAINT ORANGE (-1225 -1125);
FORCEPROP 1 LAST COMMENT_BODY TRUE
J 0
(-1025 -900);
DISPLAY 0.978723 (-1025 -900);
PAINT ORANGE (-1025 -900);
DISPLAY INVISIBLE (-1025 -900);
FORCEPROP 2 LAST CDS_LIB mstr_symbols
J 0
(-1050 -1000);
PAINT MONO (-1050 -1000);
DISPLAY INVISIBLE (-1050 -1000);
FORCEADD INTEL_CORP_BPAGE..1
(4500 -2550);
FORCEPROP 1 LAST CDS_CON_LAST_MODIFIED Fri Jun 16 17:48:56 2017
J 0
(3075 -2225);
DISPLAY 1.361702 (3075 -2225);
PAINT GREEN (3075 -2225);
DISPLAY INVISIBLE (3075 -2225);
FORCEPROP 2 LAST CUSTOM_TXT_CDS <XR_PAGE_TITLE>
J 0
(-3390 2700);
DISPLAY 0.638298 (-3390 2700);
PAINT PINK (-3390 2700);
DISPLAY INVISIBLE (-3390 2700);
FORCEPROP 2 LAST CUSTOM_TXT_CDS <CON_LAST_MODIFIED>
J 0
(500 -2450);
PAINT ORANGE (500 -2450);
FORCEPROP 2 LAST CUSTOM_TXT_CDS <CURRENT_DESIGN_SHEET> OF <TOTAL_DESIGN_SHEETS>
J 0
(4000 -2525);
PAINT ORANGE (4000 -2525);
FORCEPROP 1 LAST SCH_TITLE BMC DDR4 MEMORY
J 0
(-3450 -2500);
DISPLAY 1.212766 (-3450 -2500);
PAINT ORANGE (-3450 -2500);
FORCEPROP 1 LAST COMMENT_BODY TRUE
J 0
(4512 -2538);
DISPLAY 0.617021 (4512 -2538);
PAINT GREEN (4512 -2538);
DISPLAY INVISIBLE (4512 -2538);
FORCEPROP 2 LAST CDS_LIB mstr_symbols
J 0
(4500 -2550);
PAINT MONO (4500 -2550);
DISPLAY INVISIBLE (4500 -2550);
FORCEPROP 2 LAST PAGE_BORDER TRUE
J 0
(-3390 2700);
DISPLAY 0.851064 (-3390 2700);
PAINT PINK (-3390 2700);
DISPLAY INVISIBLE (-3390 2700);
FORCEPROP 2 LAST CDS_XR_PAGE_TITLE CR-151 : @BASEBOARD_FAB2_LIB.BASEBOARD_FAB2(SCH_1):PAGE151
J 0
(-3390 2700);
DISPLAY 0.638298 (-3390 2700);
PAINT PINK (-3390 2700);
DISPLAY INVISIBLE (-3390 2700);
FORCEADD DNS..2
(3130 1995);
PAINT RED (3130 1995);
FORCEPROP 1 LAST COMMENT_BODY TRUE
R 1
J 0
(3205 1770);
DISPLAY 0.872340 (3205 1770);
PAINT GREEN (3205 1770);
DISPLAY INVISIBLE (3205 1770);
FORCEPROP 2 LAST CDS_LIB mstr_misc
J 0
(3130 1995);
PAINT ORANGE (3130 1995);
DISPLAY INVISIBLE (3130 1995);
FORCEADD DNS..2
(-145 -1480);
PAINT RED (-145 -1480);
FORCEPROP 1 LAST COMMENT_BODY TRUE
R 1
J 0
(-70 -1705);
DISPLAY 0.872340 (-70 -1705);
PAINT GREEN (-70 -1705);
DISPLAY INVISIBLE (-70 -1705);
FORCEPROP 2 LAST CDS_LIB mstr_misc
J 0
(-145 -1480);
PAINT MONO (-145 -1480);
DISPLAY INVISIBLE (-145 -1480);
WIRE 16 -1 (950 -250)(950 -200);
WIRE 16 -1 (600 -250)(600 -200);
WIRE 16 -1 (-3225 2300)(-3225 2275);
WIRE 16 -1 (-2925 2275)(-3225 2275);
WIRE 16 -1 (-3225 2200)(-3225 2275);
WIRE 16 -1 (-2925 2275)(-2500 2275);
WIRE 16 -1 (-2925 2175)(-2925 2275);
WIRE 16 -1 (-2075 2275)(-2500 2275);
WIRE 16 -1 (-2500 2175)(-2500 2275);
WIRE 16 -1 (-2075 2200)(-2075 2275);
WIRE 16 -1 (-3225 1900)(-3225 1875);
WIRE 16 -1 (-2925 1900)(-3225 1900);
WIRE 16 -1 (-3225 2000)(-3225 1900);
WIRE 16 -1 (-2925 1900)(-2500 1900);
WIRE 16 -1 (-2925 2025)(-2925 1900);
WIRE 16 -1 (-2075 1900)(-2500 1900);
WIRE 16 -1 (-2500 2025)(-2500 1900);
WIRE 16 -1 (-2075 1900)(-2075 2000);
WIRE 16 -1 (-50 150)(-50 0);
WIRE 16 -1 (-50 0)(-200 0);
WIRE 16 -1 (625 375)(625 425);
WIRE 16 -1 (625 425)(625 675);
WIRE 16 -1 (425 425)(625 425);
WIRE 16 -1 (625 675)(625 925);
WIRE 16 -1 (425 675)(625 675);
WIRE 16 -1 (625 925)(625 1175);
WIRE 16 -1 (425 925)(625 925);
WIRE 16 -1 (625 1175)(625 1425);
WIRE 16 -1 (425 1175)(625 1175);
WIRE 16 -1 (625 1425)(625 1675);
WIRE 16 -1 (425 1425)(625 1425);
WIRE 16 -1 (425 1675)(625 1675);
WIRE 16 -1 (-150 -1400)(-150 -1350);
WIRE 16 -1 (-150 -2100)(-150 -2050);
WIRE 16 -1 (-1100 -650)(-1100 -575);
WIRE 16 -1 (-1700 -200)(-1700 -125);
WIRE 16 -1 (-2175 -275)(-2175 -375);
WIRE 16 -1 (-3400 375)(-3400 425);
WIRE 16 -1 (-3400 425)(-3400 475);
WIRE 16 -1 (-3150 425)(-3400 425);
WIRE 16 -1 (-3400 475)(-3400 525);
WIRE 16 -1 (-3150 475)(-3400 475);
WIRE 16 -1 (-3400 525)(-3400 575);
WIRE 16 -1 (-3150 525)(-3400 525);
WIRE 16 -1 (-3400 575)(-3400 625);
WIRE 16 -1 (-3150 575)(-3400 575);
WIRE 16 -1 (-3400 625)(-3400 675);
WIRE 16 -1 (-3150 625)(-3400 625);
WIRE 16 -1 (-3400 675)(-3400 725);
WIRE 16 -1 (-3150 675)(-3400 675);
WIRE 16 -1 (-3400 725)(-3400 775);
WIRE 16 -1 (-3150 725)(-3400 725);
WIRE 16 -1 (-3400 775)(-3400 825);
WIRE 16 -1 (-3150 775)(-3400 775);
WIRE 16 -1 (-3400 825)(-3400 875);
WIRE 16 -1 (-3150 825)(-3400 825);
WIRE 16 -1 (-3400 875)(-3400 925);
WIRE 16 -1 (-3150 875)(-3400 875);
WIRE 16 -1 (-3400 925)(-3400 975);
WIRE 16 -1 (-3150 925)(-3400 925);
WIRE 16 -1 (-3400 975)(-3400 1025);
WIRE 16 -1 (-3150 975)(-3400 975);
WIRE 16 -1 (-3400 1025)(-3400 1075);
WIRE 16 -1 (-3150 1025)(-3400 1025);
WIRE 16 -1 (-3400 1075)(-3400 1125);
WIRE 16 -1 (-3150 1075)(-3400 1075);
WIRE 16 -1 (-3400 1125)(-3400 1175);
WIRE 16 -1 (-3150 1125)(-3400 1125);
WIRE 16 -1 (-3400 1175)(-3400 1225);
WIRE 16 -1 (-3150 1175)(-3400 1175);
WIRE 16 -1 (-3400 1225)(-3400 1275);
WIRE 16 -1 (-3150 1225)(-3400 1225);
WIRE 16 -1 (-3400 1275)(-3400 1325);
WIRE 16 -1 (-3150 1275)(-3400 1275);
WIRE 16 -1 (-3400 1325)(-3400 1375);
WIRE 16 -1 (-3150 1325)(-3400 1325);
WIRE 16 -1 (-3400 1375)(-3400 1425);
WIRE 16 -1 (-3150 1375)(-3400 1375);
WIRE 16 -1 (-3400 1425)(-3400 1475);
WIRE 16 -1 (-3150 1425)(-3400 1425);
WIRE 16 -1 (-3400 1475)(-3400 1525);
WIRE 16 -1 (-3150 1475)(-3400 1475);
WIRE 16 -1 (-3400 1525)(-3400 1575);
WIRE 16 -1 (-3150 1525)(-3400 1525);
WIRE 16 -1 (-3400 1575)(-3400 1625);
WIRE 16 -1 (-3150 1575)(-3400 1575);
WIRE 16 -1 (-3400 1675)(-3400 1625);
WIRE 16 -1 (-3150 1625)(-3400 1625);
WIRE 16 -1 (-3150 1675)(-3400 1675);
WIRE 16 -1 (-1700 -1050)(-1700 -1000);
WIRE 16 -1 (-1675 -1400)(-1675 -1250);
WIRE 16 -1 (-2275 -1400)(-1675 -1400);
WIRE 16 -1 (-1675 -1475)(-1675 -1400);
WIRE 16 -1 (-2275 -1500)(-2275 -1400);
WIRE 16 -1 (-1675 -2400)(-1675 -2300);
WIRE 16 -1 (-1950 -2300)(-1675 -2300);
WIRE 16 -1 (-1675 -2300)(-1675 -2100);
WIRE 16 -1 (-2275 -2300)(-1950 -2300);
WIRE 16 -1 (-1950 -2300)(-1950 -2100);
WIRE 16 -1 (-2275 -2300)(-2275 -2100);
WIRE 16 -1 (1950 -2000)(1950 -2050);
WIRE 16 -1 (50 1825)(50 1675);
WIRE 16 -1 (50 1625)(50 1675);
WIRE 16 -1 (50 1675)(225 1675);
WIRE 16 -1 (-825 1675)(50 1675);
WIRE 16 -1 (50 1575)(50 1625);
WIRE 16 -1 (-825 1625)(50 1625);
WIRE 16 -1 (50 1525)(50 1575);
WIRE 16 -1 (-825 1575)(50 1575);
WIRE 16 -1 (50 1475)(50 1525);
WIRE 16 -1 (-875 1525)(50 1525);
WIRE 16 -1 (50 1425)(50 1475);
WIRE 16 -1 (-825 1475)(50 1475);
WIRE 16 -1 (50 1375)(50 1425);
WIRE 16 -1 (50 1425)(225 1425);
WIRE 16 -1 (-825 1425)(50 1425);
WIRE 16 -1 (50 1325)(50 1375);
WIRE 16 -1 (-825 1375)(50 1375);
WIRE 16 -1 (50 1275)(50 1325);
WIRE 16 -1 (-825 1325)(50 1325);
WIRE 16 -1 (50 1225)(50 1275);
WIRE 16 -1 (-825 1275)(50 1275);
WIRE 16 -1 (50 1175)(50 1225);
WIRE 16 -1 (-825 1225)(50 1225);
WIRE 16 -1 (50 1175)(50 1125);
WIRE 16 -1 (50 1175)(225 1175);
WIRE 16 -1 (-825 1175)(50 1175);
WIRE 16 -1 (50 1075)(50 1125);
WIRE 16 -1 (-825 1125)(50 1125);
WIRE 16 -1 (50 1025)(50 1075);
WIRE 16 -1 (-825 1075)(50 1075);
WIRE 16 -1 (50 975)(50 1025);
WIRE 16 -1 (-825 1025)(50 1025);
WIRE 16 -1 (50 925)(50 975);
WIRE 16 -1 (-825 975)(50 975);
WIRE 16 -1 (50 875)(50 925);
WIRE 16 -1 (50 925)(225 925);
WIRE 16 -1 (-825 925)(50 925);
WIRE 16 -1 (50 825)(50 875);
WIRE 16 -1 (-825 875)(50 875);
WIRE 16 -1 (50 775)(50 825);
WIRE 16 -1 (-825 825)(50 825);
WIRE 16 -1 (50 725)(50 775);
WIRE 16 -1 (-825 775)(50 775);
WIRE 16 -1 (50 675)(50 725);
WIRE 16 -1 (-825 725)(50 725);
WIRE 16 -1 (50 625)(50 675);
WIRE 16 -1 (50 675)(225 675);
WIRE 16 -1 (-825 675)(50 675);
WIRE 16 -1 (50 575)(50 625);
WIRE 16 -1 (-825 625)(50 625);
WIRE 16 -1 (50 525)(50 575);
WIRE 16 -1 (-825 575)(50 575);
WIRE 16 -1 (50 475)(50 525);
WIRE 16 -1 (-825 525)(50 525);
WIRE 16 -1 (50 425)(50 475);
WIRE 16 -1 (-825 475)(50 475);
WIRE 16 -1 (50 425)(225 425);
WIRE 16 -1 (-825 425)(50 425);
WIRE 16 -1 (2775 2250)(2775 2300);
WIRE 16 -1 (3350 -1400)(3350 -1500);
WIRE 16 -1 (3350 -1350)(3350 -1400);
WIRE 16 -1 (3125 -1400)(3350 -1400);
WIRE 16 -1 (3350 -1300)(3350 -1350);
WIRE 16 -1 (3125 -1350)(3350 -1350);
WIRE 16 -1 (3350 -1250)(3350 -1300);
WIRE 16 -1 (3125 -1300)(3350 -1300);
WIRE 16 -1 (3350 -1200)(3350 -1250);
WIRE 16 -1 (3125 -1250)(3350 -1250);
WIRE 16 -1 (3350 -1150)(3350 -1200);
WIRE 16 -1 (3125 -1200)(3350 -1200);
WIRE 16 -1 (3350 -1100)(3350 -1150);
WIRE 16 -1 (3125 -1150)(3350 -1150);
WIRE 16 -1 (3350 -1050)(3350 -1100);
WIRE 16 -1 (3125 -1100)(3350 -1100);
WIRE 16 -1 (3350 -1000)(3350 -1050);
WIRE 16 -1 (3125 -1050)(3350 -1050);
WIRE 16 -1 (3350 -900)(3350 -1000);
WIRE 16 -1 (3125 -1000)(3350 -1000);
WIRE 16 -1 (3350 -850)(3350 -900);
WIRE 16 -1 (3125 -900)(3350 -900);
WIRE 16 -1 (3350 -800)(3350 -850);
WIRE 16 -1 (3125 -850)(3350 -850);
WIRE 16 -1 (3350 -750)(3350 -800);
WIRE 16 -1 (3125 -800)(3350 -800);
WIRE 16 -1 (3350 -700)(3350 -750);
WIRE 16 -1 (3125 -750)(3350 -750);
WIRE 16 -1 (3350 -650)(3350 -700);
WIRE 16 -1 (3125 -700)(3350 -700);
WIRE 16 -1 (3350 -600)(3350 -650);
WIRE 16 -1 (3125 -650)(3350 -650);
WIRE 16 -1 (3350 -550)(3350 -600);
WIRE 16 -1 (3125 -600)(3350 -600);
WIRE 16 -1 (3350 -500)(3350 -550);
WIRE 16 -1 (3125 -550)(3350 -550);
WIRE 16 -1 (3350 -450)(3350 -500);
WIRE 16 -1 (3125 -500)(3350 -500);
WIRE 16 -1 (3350 -100)(3350 -450);
WIRE 16 -1 (3125 -450)(3350 -450);
WIRE 16 -1 (3125 -100)(3350 -100);
WIRE 16 -1 (1900 1450)(1900 1500);
WIRE 16 -1 (1900 1400)(1900 1450);
WIRE 16 -1 (2175 1450)(1900 1450);
WIRE 16 -1 (1900 1350)(1900 1400);
WIRE 16 -1 (2175 1400)(1900 1400);
WIRE 16 -1 (1900 1300)(1900 1350);
WIRE 16 -1 (2175 1350)(1900 1350);
WIRE 16 -1 (1900 1250)(1900 1300);
WIRE 16 -1 (2175 1300)(1900 1300);
WIRE 16 -1 (1900 1200)(1900 1250);
WIRE 16 -1 (2175 1250)(1900 1250);
WIRE 16 -1 (1900 1150)(1900 1200);
WIRE 16 -1 (2175 1200)(1900 1200);
WIRE 16 -1 (1900 1100)(1900 1150);
WIRE 16 -1 (2175 1150)(1900 1150);
WIRE 16 -1 (1900 1050)(1900 1100);
WIRE 16 -1 (2175 1100)(1900 1100);
WIRE 16 -1 (1900 1000)(1900 1050);
WIRE 16 -1 (2175 1050)(1900 1050);
WIRE 16 -1 (1900 900)(1900 1000);
WIRE 16 -1 (2175 1000)(1900 1000);
WIRE 16 -1 (1900 850)(1900 900);
WIRE 16 -1 (2175 900)(1900 900);
WIRE 16 -1 (1900 800)(1900 850);
WIRE 16 -1 (2175 850)(1900 850);
WIRE 16 -1 (1900 750)(1900 800);
WIRE 16 -1 (2175 800)(1900 800);
WIRE 16 -1 (1900 700)(1900 750);
WIRE 16 -1 (2175 750)(1900 750);
WIRE 16 -1 (1900 650)(1900 700);
WIRE 16 -1 (2175 700)(1900 700);
WIRE 16 -1 (1900 600)(1900 650);
WIRE 16 -1 (2175 650)(1900 650);
WIRE 16 -1 (1900 550)(1900 600);
WIRE 16 -1 (2175 600)(1900 600);
WIRE 16 -1 (1900 500)(1900 550);
WIRE 16 -1 (2175 550)(1900 550);
WIRE 16 -1 (1900 450)(1900 500);
WIRE 16 -1 (2175 500)(1900 500);
WIRE 16 -1 (2175 450)(1900 450);
WIRE 16 -1 (1100 700)(1100 750);
WIRE 16 -1 (1450 700)(1100 700);
WIRE 16 -1 (1100 650)(1100 700);
WIRE 16 -1 (1450 700)(1800 700);
WIRE 16 -1 (1450 700)(1450 650);
WIRE 16 -1 (1800 700)(1800 350);
WIRE 16 -1 (1800 350)(1800 300);
WIRE 16 -1 (2175 350)(1800 350);
WIRE 16 -1 (2175 300)(1800 300);
WIRE 16 -1 (1100 250)(1100 300);
WIRE 16 -1 (1450 300)(1100 300);
WIRE 16 -1 (1100 300)(1100 450);
WIRE 16 -1 (1450 450)(1450 300);
WIRE 16 -1 (-2900 975)(-1075 975);
FORCEPROP 2 LAST SIG_NAME BMC_M_A3
J 0
(-1760 985);
DISPLAY 0.680851 (-1760 985);
PAINT ORANGE (-1760 985);
FORCEPROP 2 LASTPROP $XR1 151 
J 0
(-1976 985);
DISPLAY 0.638298 (-1976 985);
PAINT MONO (-1976 985);
FORCEPROP 2 LASTPROP $XR0 143 
J 0
(-1856 985);
DISPLAY 0.638298 (-1856 985);
PAINT MONO (-1856 985);
WIRE 16 -1 (1550 -150)(2175 -150);
FORCEPROP 2 LAST SIG_NAME BMC_M_DQ11
J 0
(1615 -140);
DISPLAY 0.680851 (1615 -140);
PAINT ORANGE (1615 -140);
WIRE 16 -1 (3125 550)(3750 550);
FORCEPROP 2 LAST SIG_NAME BMC_M_CKE
J 0
(3240 560);
DISPLAY 0.680851 (3240 560);
PAINT ORANGE (3240 560);
WIRE 16 -1 (4100 1975)(3225 1975);
FORCEPROP 2 LAST SIG_NAME BMC_M_RST_N
J 0
(3590 1985);
DISPLAY 0.680851 (3590 1985);
PAINT ORANGE (3590 1985);
WIRE 3 2175 (850 2425)(4475 2425);
WIRE 3 2175 (4475 2425)(4475 1725);
WIRE 3 2175 (850 2425)(850 1725);
WIRE 3 2175 (850 1725)(4475 1725);
WIRE 16 -1 (2775 1975)(3025 1975);
WIRE 16 -1 (2775 2050)(2775 1975);
WIRE 16 -1 (2175 1975)(2775 1975);
FORCEPROP 2 LAST SIG_NAME RST_BMC_DDR3_R_N
J 0
(2240 1985);
DISPLAY 0.617021 (2240 1985);
PAINT ORANGE (2240 1985);
FORCEPROP 2 LASTPROP $XRERR UNIQUE?
J 0
(2000 1985);
DISPLAY 0.638298 (2000 1985);
PAINT MONO (2000 1985);
DISPLAY INVISIBLE (2000 1985);
WIRE 16 -1 (-2900 1625)(-1075 1625);
FORCEPROP 2 LAST SIG_NAME BMC_M_ODT
J 0
(-1760 1635);
DISPLAY 0.680851 (-1760 1635);
PAINT ORANGE (-1760 1635);
FORCEPROP 2 LASTPROP $XR1 151 
J 0
(-1976 1635);
DISPLAY 0.638298 (-1976 1635);
PAINT MONO (-1976 1635);
FORCEPROP 2 LASTPROP $XR0 143 
J 0
(-1856 1635);
DISPLAY 0.638298 (-1856 1635);
PAINT MONO (-1856 1635);
WIRE 16 -1 (-2900 1575)(-1075 1575);
FORCEPROP 2 LAST SIG_NAME BMC_M_RST_N
J 0
(-1760 1585);
DISPLAY 0.680851 (-1760 1585);
PAINT ORANGE (-1760 1585);
FORCEPROP 2 LASTPROP $XR1 151 
J 0
(-1976 1585);
DISPLAY 0.638298 (-1976 1585);
PAINT MONO (-1976 1585);
FORCEPROP 2 LASTPROP $XR0 146 
J 0
(-1856 1585);
DISPLAY 0.638298 (-1856 1585);
PAINT MONO (-1856 1585);
WIRE 16 -1 (-2900 675)(-1075 675);
FORCEPROP 2 LAST SIG_NAME BMC_M_A9
J 0
(-1760 685);
DISPLAY 0.680851 (-1760 685);
PAINT ORANGE (-1760 685);
FORCEPROP 2 LASTPROP $XR1 151 
J 0
(-1976 685);
DISPLAY 0.638298 (-1976 685);
PAINT MONO (-1976 685);
FORCEPROP 2 LASTPROP $XR0 143 
J 0
(-1856 685);
DISPLAY 0.638298 (-1856 685);
PAINT MONO (-1856 685);
WIRE 16 -1 (-2900 625)(-1075 625);
FORCEPROP 2 LAST SIG_NAME BMC_M_A10
J 0
(-1760 635);
DISPLAY 0.680851 (-1760 635);
PAINT ORANGE (-1760 635);
FORCEPROP 2 LASTPROP $XR1 151 
J 0
(-1976 635);
DISPLAY 0.638298 (-1976 635);
PAINT MONO (-1976 635);
FORCEPROP 2 LASTPROP $XR0 143 
J 0
(-1856 635);
DISPLAY 0.638298 (-1856 635);
PAINT MONO (-1856 635);
WIRE 16 -1 (-2900 575)(-1075 575);
FORCEPROP 2 LAST SIG_NAME BMC_M_A11
J 0
(-1760 585);
DISPLAY 0.680851 (-1760 585);
PAINT ORANGE (-1760 585);
FORCEPROP 2 LASTPROP $XR1 151 
J 0
(-1976 585);
DISPLAY 0.638298 (-1976 585);
PAINT MONO (-1976 585);
FORCEPROP 2 LASTPROP $XR0 143 
J 0
(-1856 585);
DISPLAY 0.638298 (-1856 585);
PAINT MONO (-1856 585);
WIRE 16 -1 (-2900 525)(-1075 525);
FORCEPROP 2 LAST SIG_NAME BMC_M_A12
J 0
(-1760 535);
DISPLAY 0.680851 (-1760 535);
PAINT ORANGE (-1760 535);
FORCEPROP 2 LASTPROP $XR1 151 
J 0
(-1976 535);
DISPLAY 0.638298 (-1976 535);
PAINT MONO (-1976 535);
FORCEPROP 2 LASTPROP $XR0 143 
J 0
(-1856 535);
DISPLAY 0.638298 (-1856 535);
PAINT MONO (-1856 535);
WIRE 16 -1 (-2900 475)(-1075 475);
FORCEPROP 2 LAST SIG_NAME BMC_M_A13
J 0
(-1760 485);
DISPLAY 0.680851 (-1760 485);
PAINT ORANGE (-1760 485);
FORCEPROP 2 LASTPROP $XR1 151 
J 0
(-1976 485);
DISPLAY 0.638298 (-1976 485);
PAINT MONO (-1976 485);
FORCEPROP 2 LASTPROP $XR0 143 
J 0
(-1856 485);
DISPLAY 0.638298 (-1856 485);
PAINT MONO (-1856 485);
WIRE 16 -1 (-2900 425)(-1075 425);
FORCEPROP 2 LAST SIG_NAME BMC_M_MACT_N
J 0
(-1760 435);
DISPLAY 0.680851 (-1760 435);
PAINT ORANGE (-1760 435);
FORCEPROP 2 LASTPROP $XR1 151 
J 0
(-1976 435);
DISPLAY 0.638298 (-1976 435);
PAINT MONO (-1976 435);
FORCEPROP 2 LASTPROP $XR0 143 
J 0
(-1856 435);
DISPLAY 0.638298 (-1856 435);
PAINT MONO (-1856 435);
WIRE 3 682 (1900 250)(1375 250);
WIRE 3 682 (1900 250)(1900 400);
WIRE 3 682 (1375 400)(1375 250);
WIRE 3 682 (1375 400)(1900 400);
WIRE 16 -1 (600 150)(600 0);
WIRE 16 -1 (550 150)(600 150);
WIRE 16 -1 (2175 150)(600 150);
FORCEPROP 2 LAST SIG_NAME BMC_M_VREFCA
J 0
(1615 160);
DISPLAY 0.680851 (1615 160);
PAINT ORANGE (1615 160);
WIRE 16 -1 (950 100)(950 0);
WIRE 16 -1 (950 100)(2175 100);
FORCEPROP 2 LAST SIG_NAME BMC_ZQ
J 0
(1615 110);
DISPLAY 0.680851 (1615 110);
PAINT ORANGE (1615 110);
FORCEPROP 2 LASTPROP $XRERR UNIQUE?
J 0
(1375 110);
DISPLAY 0.638298 (1375 110);
PAINT MONO (1375 110);
DISPLAY INVISIBLE (1375 110);
WIRE 16 -1 (1550 -1950)(1350 -1950);
WIRE 16 -1 (1350 -1550)(1550 -1550);
WIRE 16 -1 (1950 -1750)(1950 -1800);
WIRE 16 -1 (1550 -1550)(1550 -1750);
WIRE 16 -1 (1550 -1750)(1550 -1950);
WIRE 16 -1 (1550 -1750)(1950 -1750);
FORCEPROP 2 LAST SIG_NAME BMC_M_CLK
J 0
(1615 -1740);
DISPLAY 0.680851 (1615 -1740);
PAINT ORANGE (1615 -1740);
FORCEPROP 2 LASTPROP $XRERR UNIQUE?
J 0
(1375 -1740);
DISPLAY 0.638298 (1375 -1740);
PAINT MONO (1375 -1740);
DISPLAY INVISIBLE (1375 -1740);
WIRE 16 -1 (500 -1950)(1150 -1950);
FORCEPROP 2 LAST SIG_NAME BMC_M_CLK_DN
J 0
(565 -1940);
DISPLAY 0.680851 (565 -1940);
PAINT ORANGE (565 -1940);
FORCEPROP 2 LASTPROP $XR1 151 
J 0
(284 -1950);
DISPLAY 0.638298 (284 -1950);
PAINT MONO (284 -1950);
FORCEPROP 2 LASTPROP $XR0 143 
J 0
(404 -1950);
DISPLAY 0.638298 (404 -1950);
PAINT MONO (404 -1950);
WIRE 3 682 (1000 -1475)(1000 -2175);
WIRE 3 682 (2250 -1475)(1000 -1475);
WIRE 3 682 (1000 -2175)(2250 -2175);
WIRE 3 682 (2250 -2175)(2250 -1475);
WIRE 16 -1 (1550 -1400)(2175 -1400);
FORCEPROP 2 LAST SIG_NAME BMC_M_BA1
J 0
(1615 -1390);
DISPLAY 0.680851 (1615 -1390);
PAINT ORANGE (1615 -1390);
WIRE 16 -1 (1550 -1350)(2175 -1350);
FORCEPROP 2 LAST SIG_NAME BMC_M_BA0
J 0
(1615 -1340);
DISPLAY 0.680851 (1615 -1340);
PAINT ORANGE (1615 -1340);
WIRE 16 -1 (1550 -1200)(2175 -1200);
FORCEPROP 2 LAST SIG_NAME BMC_M_DM0
J 0
(1615 -1190);
DISPLAY 0.680851 (1615 -1190);
PAINT ORANGE (1615 -1190);
WIRE 16 -1 (1550 -1150)(2175 -1150);
FORCEPROP 2 LAST SIG_NAME BMC_M_DM1
J 0
(1615 -1140);
DISPLAY 0.680851 (1615 -1140);
PAINT ORANGE (1615 -1140);
WIRE 16 -1 (550 -1550)(1150 -1550);
FORCEPROP 2 LAST SIG_NAME BMC_M_CLK_DP
J 0
(615 -1540);
DISPLAY 0.680851 (615 -1540);
PAINT ORANGE (615 -1540);
FORCEPROP 2 LASTPROP $XR1 151 
J 0
(304 -1550);
DISPLAY 0.638298 (304 -1550);
PAINT MONO (304 -1550);
FORCEPROP 2 LASTPROP $XR0 143 
J 0
(424 -1550);
DISPLAY 0.638298 (424 -1550);
PAINT MONO (424 -1550);
WIRE 16 -1 (2175 -1050)(1550 -1050);
FORCEPROP 2 LAST SIG_NAME BMC_M_DQS0_DP
J 0
(1615 -1040);
DISPLAY 0.680851 (1615 -1040);
PAINT ORANGE (1615 -1040);
WIRE 16 -1 (2175 -950)(1550 -950);
FORCEPROP 2 LAST SIG_NAME BMC_M_DQS1_DP
J 0
(1615 -940);
DISPLAY 0.680851 (1615 -940);
PAINT ORANGE (1615 -940);
WIRE 16 -1 (1550 -750)(2175 -750);
FORCEPROP 2 LAST SIG_NAME BMC_M_DQ6
J 0
(1615 -740);
DISPLAY 0.680851 (1615 -740);
PAINT ORANGE (1615 -740);
WIRE 16 -1 (1550 -650)(2175 -650);
FORCEPROP 2 LAST SIG_NAME BMC_M_DQ4
J 0
(1615 -640);
DISPLAY 0.680851 (1615 -640);
PAINT ORANGE (1615 -640);
WIRE 16 -1 (1550 -550)(2175 -550);
FORCEPROP 2 LAST SIG_NAME BMC_M_DQ2
J 0
(1615 -540);
DISPLAY 0.680851 (1615 -540);
PAINT ORANGE (1615 -540);
WIRE 16 -1 (1550 -450)(2175 -450);
FORCEPROP 2 LAST SIG_NAME BMC_M_DQ0
J 0
(1615 -440);
DISPLAY 0.680851 (1615 -440);
PAINT ORANGE (1615 -440);
WIRE 16 -1 (2175 -350)(1550 -350);
FORCEPROP 2 LAST SIG_NAME BMC_M_DQ15
J 0
(1615 -340);
DISPLAY 0.680851 (1615 -340);
PAINT ORANGE (1615 -340);
WIRE 16 -1 (1550 -100)(2175 -100);
FORCEPROP 2 LAST SIG_NAME BMC_M_DQ10
J 0
(1615 -90);
DISPLAY 0.680851 (1615 -90);
PAINT ORANGE (1615 -90);
WIRE 16 -1 (1550 -50)(2175 -50);
FORCEPROP 2 LAST SIG_NAME BMC_M_DQ9
J 0
(1615 -40);
DISPLAY 0.680851 (1615 -40);
PAINT ORANGE (1615 -40);
WIRE 16 -1 (1550 0)(2175 0);
FORCEPROP 2 LAST SIG_NAME BMC_M_DQ8
J 0
(1615 10);
DISPLAY 0.680851 (1615 10);
PAINT ORANGE (1615 10);
WIRE 16 -1 (-2900 925)(-1075 925);
FORCEPROP 2 LAST SIG_NAME BMC_M_A4
J 0
(-1760 935);
DISPLAY 0.680851 (-1760 935);
PAINT ORANGE (-1760 935);
FORCEPROP 2 LASTPROP $XR1 151 
J 0
(-1976 935);
DISPLAY 0.638298 (-1976 935);
PAINT MONO (-1976 935);
FORCEPROP 2 LASTPROP $XR0 143 
J 0
(-1856 935);
DISPLAY 0.638298 (-1856 935);
PAINT MONO (-1856 935);
WIRE 16 -1 (-2900 875)(-1075 875);
FORCEPROP 2 LAST SIG_NAME BMC_M_A5
J 0
(-1760 885);
DISPLAY 0.680851 (-1760 885);
PAINT ORANGE (-1760 885);
FORCEPROP 2 LASTPROP $XR1 151 
J 0
(-1976 885);
DISPLAY 0.638298 (-1976 885);
PAINT MONO (-1976 885);
FORCEPROP 2 LASTPROP $XR0 143 
J 0
(-1856 885);
DISPLAY 0.638298 (-1856 885);
PAINT MONO (-1856 885);
WIRE 16 -1 (-2900 825)(-1075 825);
FORCEPROP 2 LAST SIG_NAME BMC_M_A6
J 0
(-1760 835);
DISPLAY 0.680851 (-1760 835);
PAINT ORANGE (-1760 835);
FORCEPROP 2 LASTPROP $XR1 151 
J 0
(-1976 835);
DISPLAY 0.638298 (-1976 835);
PAINT MONO (-1976 835);
FORCEPROP 2 LASTPROP $XR0 143 
J 0
(-1856 835);
DISPLAY 0.638298 (-1856 835);
PAINT MONO (-1856 835);
WIRE 16 -1 (-2900 775)(-1075 775);
FORCEPROP 2 LAST SIG_NAME BMC_M_A7
J 0
(-1760 785);
DISPLAY 0.680851 (-1760 785);
PAINT ORANGE (-1760 785);
FORCEPROP 2 LASTPROP $XR1 151 
J 0
(-1976 785);
DISPLAY 0.638298 (-1976 785);
PAINT MONO (-1976 785);
FORCEPROP 2 LASTPROP $XR0 143 
J 0
(-1856 785);
DISPLAY 0.638298 (-1856 785);
PAINT MONO (-1856 785);
WIRE 16 -1 (-2900 725)(-1075 725);
FORCEPROP 2 LAST SIG_NAME BMC_M_A8
J 0
(-1760 735);
DISPLAY 0.680851 (-1760 735);
PAINT ORANGE (-1760 735);
FORCEPROP 2 LASTPROP $XR1 151 
J 0
(-1976 735);
DISPLAY 0.638298 (-1976 735);
PAINT MONO (-1976 735);
FORCEPROP 2 LASTPROP $XR0 143 
J 0
(-1856 735);
DISPLAY 0.638298 (-1856 735);
PAINT MONO (-1856 735);
WIRE 16 -1 (-2900 1025)(-1075 1025);
FORCEPROP 2 LAST SIG_NAME BMC_M_A2
J 0
(-1760 1035);
DISPLAY 0.680851 (-1760 1035);
PAINT ORANGE (-1760 1035);
FORCEPROP 2 LASTPROP $XR1 151 
J 0
(-1976 1035);
DISPLAY 0.638298 (-1976 1035);
PAINT MONO (-1976 1035);
FORCEPROP 2 LASTPROP $XR0 143 
J 0
(-1856 1035);
DISPLAY 0.638298 (-1856 1035);
PAINT MONO (-1856 1035);
WIRE 16 -1 (-2900 1075)(-1075 1075);
FORCEPROP 2 LAST SIG_NAME BMC_M_A1
J 0
(-1760 1085);
DISPLAY 0.680851 (-1760 1085);
PAINT ORANGE (-1760 1085);
FORCEPROP 2 LASTPROP $XR1 151 
J 0
(-1976 1085);
DISPLAY 0.638298 (-1976 1085);
PAINT MONO (-1976 1085);
FORCEPROP 2 LASTPROP $XR0 143 
J 0
(-1856 1085);
DISPLAY 0.638298 (-1856 1085);
PAINT MONO (-1856 1085);
WIRE 16 -1 (-2900 1225)(-1075 1225);
FORCEPROP 2 LAST SIG_NAME BMC_M_BA1
J 0
(-1760 1235);
DISPLAY 0.680851 (-1760 1235);
PAINT ORANGE (-1760 1235);
FORCEPROP 2 LASTPROP $XR1 151 
J 0
(-1976 1235);
DISPLAY 0.638298 (-1976 1235);
PAINT MONO (-1976 1235);
FORCEPROP 2 LASTPROP $XR0 143 
J 0
(-1856 1235);
DISPLAY 0.638298 (-1856 1235);
PAINT MONO (-1856 1235);
WIRE 16 -1 (-2900 1325)(-1075 1325);
FORCEPROP 2 LAST SIG_NAME BMC_M_WE_N
J 0
(-1760 1335);
DISPLAY 0.680851 (-1760 1335);
PAINT ORANGE (-1760 1335);
FORCEPROP 2 LASTPROP $XR1 151 
J 0
(-1976 1335);
DISPLAY 0.638298 (-1976 1335);
PAINT MONO (-1976 1335);
FORCEPROP 2 LASTPROP $XR0 143 
J 0
(-1856 1335);
DISPLAY 0.638298 (-1856 1335);
PAINT MONO (-1856 1335);
WIRE 16 -1 (-2900 1375)(-1075 1375);
FORCEPROP 2 LAST SIG_NAME BMC_M_CAS_N
J 0
(-1760 1385);
DISPLAY 0.680851 (-1760 1385);
PAINT ORANGE (-1760 1385);
FORCEPROP 2 LASTPROP $XR1 151 
J 0
(-1976 1385);
DISPLAY 0.638298 (-1976 1385);
PAINT MONO (-1976 1385);
FORCEPROP 2 LASTPROP $XR0 143 
J 0
(-1856 1385);
DISPLAY 0.638298 (-1856 1385);
PAINT MONO (-1856 1385);
WIRE 16 -1 (-2900 1475)(-1075 1475);
FORCEPROP 2 LAST SIG_NAME BMC_M_CS_N
J 0
(-1760 1485);
DISPLAY 0.680851 (-1760 1485);
PAINT ORANGE (-1760 1485);
FORCEPROP 2 LASTPROP $XR1 151 
J 0
(-1976 1485);
DISPLAY 0.638298 (-1976 1485);
PAINT MONO (-1976 1485);
FORCEPROP 2 LASTPROP $XR0 143 
J 0
(-1856 1485);
DISPLAY 0.638298 (-1856 1485);
PAINT MONO (-1856 1485);
WIRE 16 -1 (-2900 1525)(-1075 1525);
FORCEPROP 2 LAST SIG_NAME BMC_M_MALERT_N
J 0
(-1760 1535);
DISPLAY 0.680851 (-1760 1535);
PAINT ORANGE (-1760 1535);
FORCEPROP 2 LASTPROP $XR1 151 
J 0
(-1976 1535);
DISPLAY 0.638298 (-1976 1535);
PAINT MONO (-1976 1535);
FORCEPROP 2 LASTPROP $XR0 146 
J 0
(-1856 1535);
DISPLAY 0.638298 (-1856 1535);
PAINT MONO (-1856 1535);
WIRE 16 -1 (-2900 1125)(-1075 1125);
FORCEPROP 2 LAST SIG_NAME BMC_M_A0
J 0
(-1760 1135);
DISPLAY 0.680851 (-1760 1135);
PAINT ORANGE (-1760 1135);
FORCEPROP 2 LASTPROP $XR1 151 
J 0
(-1976 1135);
DISPLAY 0.638298 (-1976 1135);
PAINT MONO (-1976 1135);
FORCEPROP 2 LASTPROP $XR0 143 
J 0
(-1856 1135);
DISPLAY 0.638298 (-1856 1135);
PAINT MONO (-1856 1135);
WIRE 16 -1 (-2900 1175)(-1075 1175);
FORCEPROP 2 LAST SIG_NAME BMC_M_BG0
J 0
(-1760 1185);
DISPLAY 0.680851 (-1760 1185);
PAINT ORANGE (-1760 1185);
FORCEPROP 2 LASTPROP $XR1 151 
J 0
(-1976 1185);
DISPLAY 0.638298 (-1976 1185);
PAINT MONO (-1976 1185);
FORCEPROP 2 LASTPROP $XR0 143 
J 0
(-1856 1185);
DISPLAY 0.638298 (-1856 1185);
PAINT MONO (-1856 1185);
WIRE 16 -1 (-2900 1275)(-1075 1275);
FORCEPROP 2 LAST SIG_NAME BMC_M_BA0
J 0
(-1760 1285);
DISPLAY 0.680851 (-1760 1285);
PAINT ORANGE (-1760 1285);
FORCEPROP 2 LASTPROP $XR1 151 
J 0
(-1976 1285);
DISPLAY 0.638298 (-1976 1285);
PAINT MONO (-1976 1285);
FORCEPROP 2 LASTPROP $XR0 143 
J 0
(-1856 1285);
DISPLAY 0.638298 (-1856 1285);
PAINT MONO (-1856 1285);
WIRE 16 -1 (-2900 1425)(-1075 1425);
FORCEPROP 2 LAST SIG_NAME BMC_M_RAS_N
J 0
(-1760 1435);
DISPLAY 0.680851 (-1760 1435);
PAINT ORANGE (-1760 1435);
FORCEPROP 2 LASTPROP $XR1 151 
J 0
(-1976 1435);
DISPLAY 0.638298 (-1976 1435);
PAINT MONO (-1976 1435);
FORCEPROP 2 LASTPROP $XR0 143 
J 0
(-1856 1435);
DISPLAY 0.638298 (-1856 1435);
PAINT MONO (-1856 1435);
WIRE 16 -1 (-2900 1675)(-1075 1675);
FORCEPROP 2 LAST SIG_NAME BMC_M_CKE
J 0
(-1760 1685);
DISPLAY 0.680851 (-1760 1685);
PAINT ORANGE (-1760 1685);
FORCEPROP 2 LASTPROP $XR1 151 
J 0
(-1976 1685);
DISPLAY 0.638298 (-1976 1685);
PAINT MONO (-1976 1685);
FORCEPROP 2 LASTPROP $XR0 143 
J 0
(-1856 1685);
DISPLAY 0.638298 (-1856 1685);
PAINT MONO (-1856 1685);
WIRE 3 682 (-2650 -1350)(-2650 -1750);
WIRE 3 682 (-2000 -1350)(-2650 -1350);
WIRE 3 682 (-2650 -1750)(-2000 -1750);
WIRE 3 682 (-2000 -1750)(-2000 -1350);
WIRE 16 -1 (1550 -200)(2175 -200);
FORCEPROP 2 LAST SIG_NAME BMC_M_DQ12
J 0
(1615 -190);
DISPLAY 0.680851 (1615 -190);
PAINT ORANGE (1615 -190);
WIRE 16 -1 (3125 1250)(3750 1250);
FORCEPROP 2 LAST SIG_NAME BMC_M_A4
J 0
(3240 1260);
DISPLAY 0.680851 (3240 1260);
PAINT ORANGE (3240 1260);
WIRE 16 -1 (3125 1300)(3750 1300);
FORCEPROP 2 LAST SIG_NAME BMC_M_A3
J 0
(3240 1310);
DISPLAY 0.680851 (3240 1310);
PAINT ORANGE (3240 1310);
WIRE 16 -1 (-2275 -1900)(-2275 -1800);
WIRE 16 -1 (-2275 -1700)(-2275 -1800);
WIRE 16 -1 (-2275 -1800)(-1950 -1800);
WIRE 16 -1 (-1950 -1900)(-1950 -1800);
WIRE 16 -1 (-1950 -1800)(-1675 -1800);
WIRE 16 -1 (-1675 -1900)(-1675 -1800);
WIRE 16 -1 (-1675 -1675)(-1675 -1800);
WIRE 16 -1 (-1225 -1800)(-1675 -1800);
FORCEPROP 2 LAST SIG_NAME BMC_M_VREFCA
J 0
(-1610 -1790);
DISPLAY 0.680851 (-1610 -1790);
PAINT ORANGE (-1610 -1790);
FORCEPROP 2 LASTPROP $XR1 143 
J 0
(-1075 -1800);
DISPLAY 0.638298 (-1075 -1800);
PAINT MONO (-1075 -1800);
FORCEPROP 2 LASTPROP $XR0 151 
J 0
(-1195 -1800);
DISPLAY 0.638298 (-1195 -1800);
PAINT MONO (-1195 -1800);
WIRE 16 -1 (3125 500)(3750 500);
FORCEPROP 2 LAST SIG_NAME BMC_M_CLK_DP
J 0
(3240 510);
DISPLAY 0.680851 (3240 510);
PAINT ORANGE (3240 510);
WIRE 16 -1 (1550 -500)(2175 -500);
FORCEPROP 2 LAST SIG_NAME BMC_M_DQ1
J 0
(1615 -490);
DISPLAY 0.680851 (1615 -490);
PAINT ORANGE (1615 -490);
WIRE 16 -1 (1550 -600)(2175 -600);
FORCEPROP 2 LAST SIG_NAME BMC_M_DQ3
J 0
(1615 -590);
DISPLAY 0.680851 (1615 -590);
PAINT ORANGE (1615 -590);
WIRE 16 -1 (1550 -700)(2175 -700);
FORCEPROP 2 LAST SIG_NAME BMC_M_DQ5
J 0
(1615 -690);
DISPLAY 0.680851 (1615 -690);
PAINT ORANGE (1615 -690);
WIRE 16 -1 (1550 -800)(2175 -800);
FORCEPROP 2 LAST SIG_NAME BMC_M_DQ7
J 0
(1615 -790);
DISPLAY 0.680851 (1615 -790);
PAINT ORANGE (1615 -790);
WIRE 16 -1 (2175 -900)(1550 -900);
FORCEPROP 2 LAST SIG_NAME BMC_M_DQS1_DN
J 0
(1615 -890);
DISPLAY 0.680851 (1615 -890);
PAINT ORANGE (1615 -890);
WIRE 16 -1 (2175 -1000)(1550 -1000);
FORCEPROP 2 LAST SIG_NAME BMC_M_DQS0_DN
J 0
(1615 -990);
DISPLAY 0.680851 (1615 -990);
PAINT ORANGE (1615 -990);
WIRE 16 -1 (1550 -250)(2175 -250);
FORCEPROP 2 LAST SIG_NAME BMC_M_DQ13
J 0
(1615 -240);
DISPLAY 0.680851 (1615 -240);
PAINT ORANGE (1615 -240);
WIRE 16 -1 (1550 -300)(2175 -300);
FORCEPROP 2 LAST SIG_NAME BMC_M_DQ14
J 0
(1615 -290);
DISPLAY 0.680851 (1615 -290);
PAINT ORANGE (1615 -290);
WIRE 16 -1 (3125 -200)(3750 -200);
FORCEPROP 2 LAST SIG_NAME BMC_M_PAR
J 0
(3415 -190);
DISPLAY 0.680851 (3415 -190);
PAINT ORANGE (3415 -190);
WIRE 16 -1 (3125 100)(3750 100);
FORCEPROP 2 LAST SIG_NAME BMC_M_ODT
J 0
(3240 110);
DISPLAY 0.680851 (3240 110);
PAINT ORANGE (3240 110);
WIRE 16 -1 (3125 200)(3750 200);
FORCEPROP 2 LAST SIG_NAME BMC_M_MALERT_N
J 0
(3240 210);
DISPLAY 0.680851 (3240 210);
PAINT ORANGE (3240 210);
WIRE 16 -1 (-150 -1850)(-150 -1750);
WIRE 16 -1 (-150 -1600)(-150 -1750);
WIRE 16 -1 (-700 -1750)(-150 -1750);
FORCEPROP 2 LAST SIG_NAME BMC_M_PAR
J 0
(-685 -1740);
DISPLAY 0.680851 (-685 -1740);
PAINT ORANGE (-685 -1740);
FORCEPROP 2 LASTPROP $XR0 151 
J 0
(-796 -1750);
DISPLAY 0.638298 (-796 -1750);
PAINT MONO (-796 -1750);
WIRE 16 -1 (-1700 -475)(-1700 -400);
WIRE 16 -1 (-1700 -475)(-1300 -475);
WIRE 16 -1 (-1700 -600)(-1700 -475);
FORCEPROP 2 LAST SIG_NAME FM_HEARTBEAT_LED
J 0
(-1685 -515);
DISPLAY 0.617021 (-1685 -515);
PAINT ORANGE (-1685 -515);
FORCEPROP 2 LASTPROP $XRERR UNIQUE?
J 0
(-1925 -515);
DISPLAY 0.638298 (-1925 -515);
PAINT MONO (-1925 -515);
DISPLAY INVISIBLE (-1925 -515);
WIRE 16 -1 (1200 1975)(1925 1975);
FORCEPROP 2 LAST SIG_NAME RST_BMC_DDR3_BUF_IN_N
J 0
(1240 1985);
DISPLAY 0.617021 (1240 1985);
PAINT ORANGE (1240 1985);
WIRE 16 -1 (3125 0)(3750 0);
FORCEPROP 2 LAST SIG_NAME BMC_M_BG0
J 0
(3240 10);
DISPLAY 0.680851 (3240 10);
PAINT ORANGE (3240 10);
WIRE 16 -1 (3125 300)(3750 300);
FORCEPROP 2 LAST SIG_NAME BMC_M_CS_N
J 0
(3240 310);
DISPLAY 0.680851 (3240 310);
PAINT ORANGE (3240 310);
WIRE 16 -1 (3125 250)(3750 250);
FORCEPROP 2 LAST SIG_NAME BMC_M_RST_N
J 0
(3240 260);
DISPLAY 0.680851 (3240 260);
PAINT ORANGE (3240 260);
WIRE 16 -1 (3125 650)(3750 650);
FORCEPROP 2 LAST SIG_NAME BMC_M_RAS_N
J 0
(3240 660);
DISPLAY 0.680851 (3240 660);
PAINT ORANGE (3240 660);
WIRE 16 -1 (3125 700)(3750 700);
FORCEPROP 2 LAST SIG_NAME BMC_M_CAS_N
J 0
(3240 710);
DISPLAY 0.680851 (3240 710);
PAINT ORANGE (3240 710);
WIRE 16 -1 (3125 750)(3750 750);
FORCEPROP 2 LAST SIG_NAME BMC_M_WE_N
J 0
(3240 760);
DISPLAY 0.680851 (3240 760);
PAINT ORANGE (3240 760);
WIRE 16 -1 (3125 850)(3750 850);
FORCEPROP 2 LAST SIG_NAME BMC_M_A12
J 0
(3240 860);
DISPLAY 0.680851 (3240 860);
PAINT ORANGE (3240 860);
WIRE 16 -1 (3125 950)(3750 950);
FORCEPROP 2 LAST SIG_NAME BMC_M_A10
J 0
(3240 960);
DISPLAY 0.680851 (3240 960);
PAINT ORANGE (3240 960);
WIRE 16 -1 (3125 1050)(3750 1050);
FORCEPROP 2 LAST SIG_NAME BMC_M_A8
J 0
(3240 1060);
DISPLAY 0.680851 (3240 1060);
PAINT ORANGE (3240 1060);
WIRE 16 -1 (3125 1150)(3750 1150);
FORCEPROP 2 LAST SIG_NAME BMC_M_A6
J 0
(3240 1160);
DISPLAY 0.680851 (3240 1160);
PAINT ORANGE (3240 1160);
WIRE 16 -1 (3125 1350)(3750 1350);
FORCEPROP 2 LAST SIG_NAME BMC_M_A2
J 0
(3240 1360);
DISPLAY 0.680851 (3240 1360);
PAINT ORANGE (3240 1360);
WIRE 16 -1 (3125 1450)(3750 1450);
FORCEPROP 2 LAST SIG_NAME BMC_M_A0
J 0
(3240 1460);
DISPLAY 0.680851 (3240 1460);
PAINT ORANGE (3240 1460);
WIRE 16 -1 (3125 1400)(3750 1400);
FORCEPROP 2 LAST SIG_NAME BMC_M_A1
J 0
(3240 1410);
DISPLAY 0.680851 (3240 1410);
PAINT ORANGE (3240 1410);
WIRE 16 -1 (3125 1200)(3750 1200);
FORCEPROP 2 LAST SIG_NAME BMC_M_A5
J 0
(3240 1210);
DISPLAY 0.680851 (3240 1210);
PAINT ORANGE (3240 1210);
WIRE 16 -1 (3125 800)(3750 800);
FORCEPROP 2 LAST SIG_NAME BMC_M_A13
J 0
(3240 810);
DISPLAY 0.680851 (3240 810);
PAINT ORANGE (3240 810);
WIRE 16 -1 (3125 1100)(3750 1100);
FORCEPROP 2 LAST SIG_NAME BMC_M_A7
J 0
(3240 1110);
DISPLAY 0.680851 (3240 1110);
PAINT ORANGE (3240 1110);
WIRE 16 -1 (3125 1000)(3750 1000);
FORCEPROP 2 LAST SIG_NAME BMC_M_A9
J 0
(3240 1010);
DISPLAY 0.680851 (3240 1010);
PAINT ORANGE (3240 1010);
WIRE 16 -1 (3125 450)(3750 450);
FORCEPROP 2 LAST SIG_NAME BMC_M_CLK_DN
J 0
(3240 460);
DISPLAY 0.680851 (3240 460);
PAINT ORANGE (3240 460);
WIRE 16 -1 (3125 350)(3750 350);
FORCEPROP 2 LAST SIG_NAME BMC_M_MACT_N
J 0
(3240 360);
DISPLAY 0.680851 (3240 360);
PAINT ORANGE (3240 360);
WIRE 16 -1 (-2175 -575)(-2175 -900);
WIRE 16 -1 (-2175 -900)(-1900 -900);
WIRE 16 -1 (-2900 -900)(-2175 -900);
FORCEPROP 2 LAST SIG_NAME FM_BMC_HEARTBEAT_N
J 0
(-2835 -890);
DISPLAY 0.617021 (-2835 -890);
PAINT ORANGE (-2835 -890);
WIRE 16 -1 (-1100 0)(-1100 -175);
WIRE 16 -1 (-1000 0)(-1100 0);
FORCEPROP 2 LAST SIG_NAME FM_HEARTBEAT_LED_K
J 0
(-1410 10);
DISPLAY 0.617021 (-1410 10);
PAINT ORANGE (-1410 10);
FORCEPROP 2 LASTPROP $XRERR UNIQUE?
J 0
(-1650 10);
DISPLAY 0.638298 (-1650 10);
PAINT MONO (-1650 10);
DISPLAY INVISIBLE (-1650 10);
WIRE 16 -1 (3125 900)(3750 900);
FORCEPROP 2 LAST SIG_NAME BMC_M_A11
J 0
(3240 910);
DISPLAY 0.680851 (3240 910);
PAINT ORANGE (3240 910);
WIRE 16 -1 (-400 0)(-800 0);
FORCEPROP 2 LAST SIG_NAME FM_HEARTBEAT_LED_A
J 0
(-810 10);
DISPLAY 0.617021 (-810 10);
PAINT ORANGE (-810 10);
FORCEPROP 2 LASTPROP $XRERR UNIQUE?
J 0
(-1050 10);
DISPLAY 0.638298 (-1050 10);
PAINT MONO (-1050 10);
DISPLAY INVISIBLE (-1050 10);
DOT 1 (625 425);
DOT 1 (50 1075);
DOT 1 (50 425);
DOT 1 (50 625);
DOT 1 (50 675);
DOT 1 (50 725);
DOT 1 (50 775);
DOT 1 (50 875);
DOT 1 (50 825);
DOT 1 (50 925);
DOT 1 (50 975);
DOT 1 (625 925);
DOT 1 (50 1025);
DOT 1 (50 1275);
DOT 1 (50 1175);
DOT 1 (50 1325);
DOT 1 (50 1375);
DOT 1 (50 1525);
DOT 1 (50 1475);
DOT 1 (50 1425);
DOT 1 (50 1625);
DOT 1 (50 1575);
DOT 1 (50 1675);
DOT 1 (625 1175);
DOT 1 (-3400 1375);
DOT 1 (3350 -1350);
DOT 1 (1900 1000);
DOT 1 (1800 350);
DOT 1 (1900 900);
DOT 1 (1900 800);
DOT 1 (1900 700);
DOT 1 (1900 1100);
DOT 1 (1900 1050);
DOT 1 (1900 550);
DOT 1 (1900 1350);
DOT 1 (1900 1400);
DOT 1 (3350 -700);
DOT 1 (-1675 -2300);
DOT 1 (-1950 -2300);
DOT 1 (3350 -800);
DOT 1 (-150 -1750);
DOT 1 (1900 1450);
DOT 1 (1100 300);
DOT 1 (3350 -1400);
DOT 1 (3350 -1300);
DOT 1 (3350 -1250);
DOT 1 (3350 -1150);
DOT 1 (3350 -1100);
DOT 1 (3350 -1050);
DOT 1 (3350 -1000);
DOT 1 (3350 -900);
DOT 1 (3350 -850);
DOT 1 (3350 -650);
DOT 1 (3350 -550);
DOT 1 (3350 -500);
DOT 1 (3350 -450);
DOT 1 (1900 500);
DOT 1 (1900 600);
DOT 1 (1900 650);
DOT 1 (1900 1150);
DOT 1 (1900 1200);
DOT 1 (1900 1250);
DOT 1 (1900 1300);
DOT 1 (-2275 -1800);
DOT 1 (-1675 -1800);
DOT 1 (-2175 -900);
DOT 1 (-3400 425);
DOT 1 (-3400 475);
DOT 1 (-3400 575);
DOT 1 (-3400 525);
DOT 1 (-3400 625);
DOT 1 (-3400 675);
DOT 1 (-3400 725);
DOT 1 (-3400 825);
DOT 1 (-3400 775);
DOT 1 (-3400 875);
DOT 1 (-3400 925);
DOT 1 (-3400 975);
DOT 1 (-3400 1075);
DOT 1 (-3400 1025);
DOT 1 (-3400 1125);
DOT 1 (-3400 1175);
DOT 1 (-3400 1225);
DOT 1 (-3400 1325);
DOT 1 (-3400 1425);
DOT 1 (-3400 1475);
DOT 1 (-3400 1525);
DOT 1 (-3400 1625);
DOT 1 (-1675 -1400);
DOT 1 (-1700 -475);
DOT 1 (3350 -600);
DOT 1 (3350 -750);
DOT 1 (3350 -1200);
DOT 1 (2775 1975);
DOT 1 (-1950 -1800);
DOT 1 (600 150);
DOT 1 (-3400 1275);
DOT 1 (-3400 1575);
DOT 1 (1900 850);
DOT 1 (-2925 2275);
DOT 1 (-3225 2275);
DOT 1 (-2925 1900);
DOT 1 (-3225 1900);
DOT 1 (50 1125);
DOT 1 (50 475);
DOT 1 (50 525);
DOT 1 (50 575);
DOT 1 (625 675);
DOT 1 (625 1425);
DOT 1 (50 1225);
DOT 1 (1900 750);
DOT 1 (1450 700);
DOT 1 (1100 700);
DOT 1 (-2500 2275);
DOT 1 (1550 -1750);
DOT 1 (-2500 1900);
FORCENOTE
TP FAB3 NOPOP R25W3, 4, 29 0803
(-3400 1750) 0;
DISPLAY LEFT (-3400 1750);
DISPLAY 1.021277 (-3400 1750);
PAINT RED (-3400 1750);
FORCENOTE
TRACE WIDTH >= 15 MILS
(-1475 -1950) 0;
DISPLAY LEFT (-1475 -1950);
DISPLAY 1.021277 (-1475 -1950);
PAINT PURPLE (-1475 -1950);
FORCENOTE
ROOM=SM_CONTROLLER
(-2983 -2277) 0;
DISPLAY LEFT (-2983 -2277);
DISPLAY 0.617021 (-2983 -2277);
PAINT PURPLE (-2983 -2277);
FORCENOTE
TP FAB3 NOPOP CAP 0805
(-2725 -1325) 0;
DISPLAY LEFT (-2725 -1325);
DISPLAY 1.021277 (-2725 -1325);
PAINT RED (-2725 -1325);
FORCENOTE
TP FAB3 CHANGE RES 0823
(2275 -2150) 0;
DISPLAY LEFT (2275 -2150);
DISPLAY 0.638298 (2275 -2150);
PAINT RED (2275 -2150);
FORCENOTE
TP FAB3 ADD RES AND CAP 0803
(2275 -2100) 0;
DISPLAY LEFT (2275 -2100);
DISPLAY 0.638298 (2275 -2100);
PAINT RED (2275 -2100);
FORCENOTE
R1T40 AND R1T28 SHOULD BE 50 OHM
(2275 -2050) 0;
DISPLAY LEFT (2275 -2050);
DISPLAY 0.638298 (2275 -2050);
PAINT PURPLE (2275 -2050);
FORCENOTE
TP FAB3 CHANGE R25W30 0803
(-1275 1725) 0;
DISPLAY LEFT (-1275 1725);
DISPLAY 1.021277 (-1275 1725);
PAINT RED (-1275 1725);
FORCENOTE
TP FAB1 CHANGE CONNECTION 0330
(1175 200) 0;
DISPLAY LEFT (1175 200);
DISPLAY 1.021277 (1175 200);
PAINT RED (1175 200);
FORCENOTE
TP FAB1 NOPOP R9F34 0121
(3200 2100) 0;
DISPLAY LEFT (3200 2100);
DISPLAY 1.021277 (3200 2100);
PAINT RED (3200 2100);
FORCENOTE
TP FAB4 NOPOP U9F3 AND R9F29 20170206
(1900 1675) 0;
DISPLAY LEFT (1900 1675);
DISPLAY 0.638298 (1900 1675);
PAINT RED (1900 1675);
QUIT
